%FSTAX23Y23*%
%MOIN*%
%SFA1B1*%

%IPPOS*%
%ADD142C,0.120000*%
%ADD170C,0.061020*%
%ADD172C,0.075000*%
%ADD173C,0.098430*%
%ADD175O,0.177170X0.088580*%
%ADD176O,0.088580X0.177170*%
%ADD181C,0.016000*%
%ADD183C,0.200000*%
%LNtimingcard_pcb-1*%
%LPD*%
G36*
X07078Y00509D02*
X03114D01*
Y00225*
X02294*
Y00314*
X02262Y00346*
X02234*
X02202Y00314*
Y00225*
X01781*
Y00341*
X01784Y00342*
X01786Y00343*
X01791Y00339*
X01797Y00338*
X01804Y00339*
X01809Y00343*
X01812Y00348*
X01814Y00355*
X01812Y00361*
X01809Y00366*
X01804Y0037*
X01797Y00371*
X01791Y0037*
X01786Y00366*
X01784Y00367*
X01781Y00368*
Y00469*
X01735Y00515*
X01663*
X01618Y0047*
Y00312*
X01321*
Y00512*
X00581*
Y00188*
X00007*
Y04354*
X00019Y04366*
X07078*
Y00509*
G37*
%LNtimingcard_pcb-2*%
%LPC*%
G36*
X0257Y04299D02*
X02564Y04298D01*
X02559Y04294*
X02555Y04289*
X02554Y04283*
X02555Y04276*
X02559Y04271*
X02564Y04267*
X0257Y04266*
X02577Y04267*
X02582Y04271*
X02585Y04276*
X02587Y04283*
X02585Y04289*
X02582Y04294*
X02577Y04298*
X0257Y04299*
G37*
G36*
X01294Y04272D02*
X01288Y04271D01*
X01283Y04267*
X01279Y04262*
X01278Y04256*
X01279Y04249*
X01283Y04244*
X01288Y0424*
X01294Y04239*
X01301Y0424*
X01306Y04244*
X01309Y04249*
X01311Y04256*
X01309Y04262*
X01306Y04267*
X01301Y04271*
X01294Y04272*
G37*
G36*
X02078Y04293D02*
X02007D01*
Y04222*
X02078*
Y04293*
G37*
G36*
X01493Y04289D02*
X01422D01*
Y04218*
X01493*
Y04289*
G37*
G36*
X01557Y04245D02*
X01551Y04244D01*
X01546Y0424*
X01542Y04235*
X01541Y04229*
X01542Y04222*
X01546Y04217*
X01551Y04213*
X01557Y04212*
X01564Y04213*
X01569Y04217*
X01572Y04222*
X01574Y04229*
X01572Y04235*
X01569Y0424*
X01564Y04244*
X01557Y04245*
G37*
G36*
X01345Y04191D02*
X01339Y0419D01*
X01333Y04186*
X0133Y04181*
X01329Y04175*
X0133Y04168*
X01333Y04163*
X01339Y0416*
X01345Y04158*
X01351Y0416*
X01357Y04163*
X0136Y04168*
X01361Y04175*
X0136Y04181*
X01357Y04186*
X01351Y0419*
X01345Y04191*
G37*
G36*
X01569Y04187D02*
X01563Y04186D01*
X01558Y04182*
X01554Y04177*
X01553Y04171*
X01554Y04165*
X01558Y04159*
X01563Y04156*
X01569Y04154*
X01576Y04156*
X01581Y04159*
X01584Y04165*
X01586Y04171*
X01584Y04177*
X01581Y04182*
X01576Y04186*
X01569Y04187*
G37*
G36*
X01779Y04172D02*
X01773Y04171D01*
X01768Y04167*
X01764Y04162*
X01763Y04156*
X01764Y04149*
X01768Y04144*
X01773Y0414*
X01779Y04139*
X01786Y0414*
X01791Y04144*
X01794Y04149*
X01796Y04156*
X01794Y04162*
X01791Y04167*
X01786Y04171*
X01779Y04172*
G37*
G36*
X02043Y04193D02*
X02034Y04192D01*
X02025Y04188*
X02017Y04183*
X02012Y04175*
X02008Y04167*
X02007Y04157*
X02008Y04148*
X02012Y04139*
X02017Y04132*
X02025Y04126*
X02034Y04123*
X02043Y04122*
X02052Y04123*
X02061Y04126*
X02068Y04132*
X02074Y04139*
X02077Y04148*
X02079Y04157*
X02077Y04167*
X02074Y04175*
X02068Y04183*
X02061Y04188*
X02052Y04192*
X02043Y04193*
G37*
G36*
X01457Y04189D02*
X01448Y04188D01*
X01439Y04184*
X01432Y04179*
X01426Y04171*
X01423Y04163*
X01421Y04153*
X01423Y04144*
X01426Y04136*
X01432Y04128*
X01439Y04122*
X01448Y04119*
X01457Y04118*
X01466Y04119*
X01475Y04122*
X01483Y04128*
X01488Y04136*
X01492Y04144*
X01493Y04153*
X01492Y04163*
X01488Y04171*
X01483Y04179*
X01475Y04184*
X01466Y04188*
X01457Y04189*
G37*
G36*
X03958Y04152D02*
X03951Y04151D01*
X03945Y04148*
X03939Y04144*
X03935Y04139*
X03933Y04132*
X03932Y04126*
X03933Y04119*
X03935Y04113*
X03939Y04107*
X03945Y04103*
X03951Y04101*
X03958Y041*
X03964Y04101*
X03971Y04103*
X03976Y04107*
X0398Y04113*
X03983Y04119*
X03984Y04126*
X03983Y04132*
X0398Y04139*
X03976Y04144*
X03971Y04148*
X03964Y04151*
X03958Y04152*
G37*
G36*
X03784D02*
X03778Y04151D01*
X03771Y04148*
X03766Y04144*
X03762Y04139*
X03759Y04132*
X03758Y04126*
X03759Y04119*
X03762Y04113*
X03766Y04107*
X03771Y04103*
X03778Y04101*
X03784Y041*
X03791Y04101*
X03797Y04103*
X03803Y04107*
X03807Y04113*
X03809Y04119*
X0381Y04126*
X03809Y04132*
X03807Y04139*
X03803Y04144*
X03797Y04148*
X03791Y04151*
X03784Y04152*
G37*
G36*
X04754Y04132D02*
X04748Y04131D01*
X04743Y04127*
X04739Y04122*
X04738Y04115*
X04739Y04109*
X04743Y04104*
X04748Y041*
X04754Y04099*
X0476Y041*
X04766Y04104*
X04769Y04109*
X04771Y04115*
X04769Y04122*
X04766Y04127*
X0476Y04131*
X04754Y04132*
G37*
G36*
X02146Y0412D02*
X02139Y04118D01*
X02134Y04115*
X02131Y0411*
X02129Y04103*
X02131Y04097*
X02134Y04092*
X02139Y04088*
X02146Y04087*
X02152Y04088*
X02157Y04092*
X02161Y04097*
X02162Y04103*
X02161Y0411*
X02157Y04115*
X02152Y04118*
X02146Y0412*
G37*
G36*
X0522Y04102D02*
X05214Y04101D01*
X05208Y04098*
X05205Y04092*
X05204Y04086*
X05205Y0408*
X05208Y04075*
X05214Y04071*
X0522Y0407*
X05226Y04071*
X05232Y04075*
X05235Y0408*
X05236Y04086*
X05235Y04092*
X05232Y04098*
X05226Y04101*
X0522Y04102*
G37*
G36*
X02253D02*
X02247Y04101D01*
X02242Y04098*
X02238Y04092*
X02237Y04086*
X02238Y0408*
X02242Y04075*
X02247Y04071*
X02253Y0407*
X0226Y04071*
X02265Y04075*
X02269Y0408*
X0227Y04086*
X02269Y04092*
X02265Y04098*
X0226Y04101*
X02253Y04102*
G37*
G36*
X03504Y04102D02*
X03498Y04101D01*
X03493Y04097*
X03489Y04092*
X03488Y04086*
X03489Y04079*
X03493Y04074*
X03498Y0407*
X03504Y04069*
X03511Y0407*
X03516Y04074*
X03519Y04079*
X03521Y04086*
X03519Y04092*
X03516Y04097*
X03511Y04101*
X03504Y04102*
G37*
G36*
X03294Y04127D02*
X03284Y04126D01*
X03274Y04121*
X03265Y04115*
X03259Y04106*
X03254Y04096*
X03253Y04086*
X03254Y04075*
X03259Y04065*
X03265Y04056*
X03274Y0405*
X03284Y04046*
X03294Y04044*
X03305Y04046*
X03315Y0405*
X03324Y04056*
X0333Y04065*
X03334Y04075*
X03336Y04086*
X03334Y04096*
X0333Y04106*
X03324Y04115*
X03315Y04121*
X03305Y04126*
X03294Y04127*
G37*
G36*
X02994D02*
X02984Y04126D01*
X02974Y04121*
X02965Y04115*
X02959Y04106*
X02954Y04096*
X02953Y04086*
X02954Y04075*
X02959Y04065*
X02965Y04056*
X02974Y0405*
X02984Y04046*
X02994Y04044*
X03005Y04046*
X03015Y0405*
X03024Y04056*
X0303Y04065*
X03034Y04075*
X03036Y04086*
X03034Y04096*
X0303Y04106*
X03024Y04115*
X03015Y04121*
X03005Y04126*
X02994Y04127*
G37*
G36*
X069Y0416D02*
X06887Y04159D01*
X06874Y04155*
X06862Y04149*
X06852Y04141*
X06844Y0413*
X06837Y04119*
X06834Y04106*
X06832Y04093*
X06834Y0408*
X06837Y04067*
X06844Y04056*
X06852Y04045*
X06862Y04037*
X06874Y04031*
X06887Y04027*
X069Y04026*
X06913Y04027*
X06925Y04031*
X06937Y04037*
X06947Y04045*
X06956Y04056*
X06962Y04067*
X06966Y0408*
X06967Y04093*
X06966Y04106*
X06962Y04119*
X06956Y0413*
X06947Y04141*
X06937Y04149*
X06925Y04155*
X06913Y04159*
X069Y0416*
G37*
G36*
X06569D02*
X06556Y04159D01*
X06543Y04155*
X06532Y04149*
X06521Y04141*
X06513Y0413*
X06507Y04119*
X06503Y04106*
X06502Y04093*
X06503Y0408*
X06507Y04067*
X06513Y04056*
X06521Y04045*
X06532Y04037*
X06543Y04031*
X06556Y04027*
X06569Y04026*
X06582Y04027*
X06595Y04031*
X06606Y04037*
X06617Y04045*
X06625Y04056*
X06631Y04067*
X06635Y0408*
X06636Y04093*
X06635Y04106*
X06631Y04119*
X06625Y0413*
X06617Y04141*
X06606Y04149*
X06595Y04155*
X06582Y04159*
X06569Y0416*
G37*
G36*
X02043Y04093D02*
X02034Y04092D01*
X02025Y04088*
X02017Y04083*
X02012Y04075*
X02008Y04067*
X02007Y04057*
X02008Y04048*
X02012Y04039*
X02017Y04032*
X02025Y04026*
X02034Y04023*
X02043Y04022*
X02052Y04023*
X02061Y04026*
X02068Y04032*
X02074Y04039*
X02077Y04048*
X02079Y04057*
X02077Y04067*
X02074Y04075*
X02068Y04083*
X02061Y04088*
X02052Y04092*
X02043Y04093*
G37*
G36*
X00285Y04285D02*
X00264Y04283D01*
X00244Y04278*
X00224Y0427*
X00207Y04259*
X00191Y04246*
X00177Y0423*
X00166Y04212*
X00158Y04193*
X00153Y04172*
X00152Y04152*
X00153Y04131*
X00158Y0411*
X00166Y04091*
X00177Y04073*
X00191Y04057*
X00207Y04044*
X00224Y04033*
X00244Y04025*
X00264Y0402*
X00285Y04018*
X00306Y0402*
X00326Y04025*
X00346Y04033*
X00363Y04044*
X00379Y04057*
X00393Y04073*
X00404Y04091*
X00412Y0411*
X00417Y04131*
X00418Y04152*
X00417Y04172*
X00412Y04193*
X00404Y04212*
X00393Y0423*
X00379Y04246*
X00363Y04259*
X00346Y0427*
X00326Y04278*
X00306Y04283*
X00285Y04285*
G37*
G36*
X01457Y04089D02*
X01448Y04088D01*
X01439Y04084*
X01432Y04079*
X01426Y04071*
X01423Y04063*
X01421Y04053*
X01423Y04044*
X01426Y04036*
X01432Y04028*
X01439Y04022*
X01448Y04019*
X01457Y04018*
X01466Y04019*
X01475Y04022*
X01483Y04028*
X01488Y04036*
X01492Y04044*
X01493Y04053*
X01492Y04063*
X01488Y04071*
X01483Y04079*
X01475Y04084*
X01466Y04088*
X01457Y04089*
G37*
G36*
X01903Y04034D02*
X01897Y04033D01*
X01892Y04029*
X01888Y04024*
X01887Y04018*
X01888Y04011*
X01892Y04006*
X01897Y04002*
X01903Y04001*
X0191Y04002*
X01915Y04006*
X01918Y04011*
X0192Y04018*
X01918Y04024*
X01915Y04029*
X0191Y04033*
X01903Y04034*
G37*
G36*
X02353Y04034D02*
X02347Y04032D01*
X02341Y04029*
X02338Y04023*
X02337Y04017*
X02338Y04011*
X02341Y04006*
X02347Y04002*
X02353Y04001*
X02359Y04002*
X02364Y04006*
X02368Y04011*
X02369Y04017*
X02368Y04023*
X02364Y04029*
X02359Y04032*
X02353Y04034*
G37*
G36*
X05723Y04083D02*
X05708Y04081D01*
X05694Y04075*
X05682Y04066*
X05673Y04054*
X05667Y0404*
X05665Y04025*
X05667Y0401*
X05673Y03996*
X05682Y03984*
X05694Y03975*
X05708Y03969*
X05723Y03967*
X05738Y03969*
X05752Y03975*
X05764Y03984*
X05773Y03996*
X05779Y0401*
X05781Y04025*
X05779Y0404*
X05773Y04054*
X05764Y04066*
X05752Y04075*
X05738Y04081*
X05723Y04083*
G37*
G36*
X01408Y03996D02*
X01402Y03995D01*
X01396Y03991*
X01393Y03986*
X01392Y0398*
X01393Y03974*
X01396Y03968*
X01402Y03965*
X01408Y03964*
X01414Y03965*
X0142Y03968*
X01423Y03974*
X01424Y0398*
X01423Y03986*
X0142Y03991*
X01414Y03995*
X01408Y03996*
G37*
G36*
X04393Y03992D02*
X04387Y03991D01*
X04382Y03987*
X04378Y03982*
X04377Y03976*
X04378Y0397*
X04382Y03964*
X04387Y03961*
X04393Y0396*
X04399Y03961*
X04405Y03964*
X04408Y0397*
X0441Y03976*
X04408Y03982*
X04405Y03987*
X04399Y03991*
X04393Y03992*
G37*
G36*
X02084Y03912D02*
X02078Y03911D01*
X02073Y03907*
X02069Y03902*
X02068Y03896*
X02069Y03889*
X02069Y03889*
X02066Y03885*
X02066Y03886*
X02059Y03887*
X02053Y03886*
X02048Y03882*
X02044Y03877*
X02043Y03871*
X02044Y03864*
X02048Y03859*
X02053Y03855*
X02059Y03854*
X02066Y03855*
X02071Y03859*
X02074Y03864*
X02076Y03871*
X02074Y03877*
X02074Y03877*
X02078Y03881*
X02078Y0388*
X02084Y03879*
X02091Y0388*
X02096Y03884*
X02099Y03889*
X02101Y03896*
X02099Y03902*
X02096Y03907*
X02091Y03911*
X02084Y03912*
G37*
G36*
X02029Y03852D02*
X02023Y03851D01*
X02018Y03847*
X02014Y03842*
X02013Y03836*
X02013Y03835*
X02013Y03834*
X02009Y03831*
X02004Y03832*
X01998Y03831*
X01993Y03827*
X01989Y03822*
X01988Y03816*
X01989Y03809*
X01993Y03804*
X01998Y038*
X02004Y03799*
X02011Y038*
X02016Y03804*
X02019Y03809*
X02021Y03816*
X02021Y03816*
X02021Y03817*
X02025Y0382*
X02029Y03819*
X02036Y0382*
X02041Y03824*
X02044Y03829*
X02046Y03836*
X02044Y03842*
X02041Y03847*
X02036Y03851*
X02029Y03852*
G37*
G36*
X03699D02*
X03693Y03851D01*
X03688Y03847*
X03684Y03842*
X03683Y03836*
X03684Y03829*
X03688Y03824*
X03693Y0382*
X03699Y03819*
X03706Y0382*
X03711Y03824*
X03714Y03829*
X03716Y03836*
X03714Y03842*
X03711Y03847*
X03706Y03851*
X03699Y03852*
G37*
G36*
X03014Y03847D02*
X03008Y03846D01*
X03003Y03842*
X02999Y03837*
X02998Y03831*
X02999Y03824*
X03003Y03819*
X03008Y03815*
X03014Y03814*
X03021Y03815*
X03026Y03819*
X03029Y03824*
X03031Y03831*
X03029Y03837*
X03026Y03842*
X03021Y03846*
X03014Y03847*
G37*
G36*
X03829Y03822D02*
X03823Y03821D01*
X03818Y03817*
X03814Y03812*
X03813Y03806*
X03814Y03799*
X03818Y03794*
X03823Y0379*
X03829Y03789*
X03836Y0379*
X03841Y03794*
X03844Y03799*
X03846Y03806*
X03844Y03812*
X03841Y03817*
X03836Y03821*
X03829Y03822*
G37*
G36*
X03539D02*
X03533Y03821D01*
X03528Y03817*
X03524Y03812*
X03523Y03806*
X03524Y03799*
X03528Y03794*
X03533Y0379*
X03539Y03789*
X03546Y0379*
X03551Y03794*
X03554Y03799*
X03556Y03806*
X03554Y03812*
X03551Y03817*
X03546Y03821*
X03539Y03822*
G37*
G36*
X03219D02*
X03213Y03821D01*
X03208Y03817*
X03204Y03812*
X03203Y03806*
X03204Y03799*
X03208Y03794*
X03213Y0379*
X03219Y03789*
X03226Y0379*
X03231Y03794*
X03234Y03799*
X03236Y03806*
X03234Y03812*
X03231Y03817*
X03226Y03821*
X03219Y03822*
G37*
G36*
X05723Y03902D02*
X05708Y039D01*
X05694Y03894*
X05682Y03885*
X05673Y03873*
X05667Y03859*
X05665Y03844*
X05667Y03829*
X05673Y03815*
X05682Y03803*
X05694Y03794*
X05708Y03788*
X05723Y03786*
X05738Y03788*
X05752Y03794*
X05764Y03803*
X05773Y03815*
X05779Y03829*
X05781Y03844*
X05779Y03859*
X05773Y03873*
X05764Y03885*
X05752Y03894*
X05738Y039*
X05723Y03902*
G37*
G36*
X02722Y03802D02*
X02716Y03801D01*
X0271Y03797*
X02707Y03792*
X02706Y03786*
X02707Y03779*
X0271Y03774*
X02716Y03771*
X02722Y03769*
X02728Y03771*
X02733Y03774*
X02737Y03779*
X02738Y03786*
X02737Y03792*
X02733Y03797*
X02728Y03801*
X02722Y03802*
G37*
G36*
X06169Y03877D02*
X0607D01*
X06055Y03875*
X06041Y03869*
X06029Y0386*
X0602Y03848*
X06014Y03834*
X06012Y03819*
X06014Y03804*
X0602Y0379*
X06029Y03779*
X06041Y03769*
X06055Y03764*
X0607Y03762*
X06169*
X06183Y03764*
X06197Y03769*
X06209Y03779*
X06219Y0379*
X06224Y03804*
X06226Y03819*
X06224Y03834*
X06219Y03848*
X06209Y0386*
X06197Y03869*
X06183Y03875*
X06169Y03877*
G37*
G36*
X04254Y03792D02*
X04248Y03791D01*
X04243Y03787*
X04239Y03782*
X04238Y03776*
X04239Y03769*
X04243Y03764*
X04248Y0376*
X04254Y03759*
X04261Y0376*
X04266Y03764*
X04269Y03769*
X04271Y03776*
X04269Y03782*
X04266Y03787*
X04261Y03791*
X04254Y03792*
G37*
G36*
X069Y03863D02*
X06885Y03861D01*
X06871Y03856*
X06859Y03846*
X0685Y03834*
X06844Y03821*
X06842Y03806*
X06844Y03791*
X0685Y03777*
X06859Y03765*
X06871Y03756*
X06885Y0375*
X069Y03748*
X06915Y0375*
X06929Y03756*
X06941Y03765*
X0695Y03777*
X06955Y03791*
X06957Y03806*
X06955Y03821*
X0695Y03834*
X06941Y03846*
X06929Y03856*
X06915Y03861*
X069Y03863*
G37*
G36*
X06734D02*
X06719Y03861D01*
X06705Y03856*
X06694Y03846*
X06684Y03834*
X06679Y03821*
X06677Y03806*
X06679Y03791*
X06684Y03777*
X06694Y03765*
X06705Y03756*
X06719Y0375*
X06734Y03748*
X06749Y0375*
X06763Y03756*
X06775Y03765*
X06784Y03777*
X0679Y03791*
X06792Y03806*
X0679Y03821*
X06784Y03834*
X06775Y03846*
X06763Y03856*
X06749Y03861*
X06734Y03863*
G37*
G36*
X06569D02*
X06554Y03861D01*
X0654Y03856*
X06528Y03846*
X06519Y03834*
X06513Y03821*
X06511Y03806*
X06513Y03791*
X06519Y03777*
X06528Y03765*
X0654Y03756*
X06554Y0375*
X06569Y03748*
X06584Y0375*
X06598Y03756*
X0661Y03765*
X06619Y03777*
X06625Y03791*
X06627Y03806*
X06625Y03821*
X06619Y03834*
X0661Y03846*
X06598Y03856*
X06584Y03861*
X06569Y03863*
G37*
G36*
X03699Y03767D02*
X03693Y03766D01*
X03688Y03762*
X03684Y03757*
X03683Y03751*
X03684Y03744*
X03688Y03739*
X03693Y03735*
X03699Y03734*
X03706Y03735*
X03711Y03739*
X03714Y03744*
X03716Y03751*
X03714Y03757*
X03711Y03762*
X03706Y03766*
X03699Y03767*
G37*
G36*
X02993D02*
X02987Y03766D01*
X02981Y03762*
X02978Y03757*
X02977Y03751*
X02978Y03744*
X02981Y03739*
X02987Y03735*
X02993Y03734*
X02999Y03735*
X03004Y03739*
X03008Y03744*
X03009Y03751*
X03008Y03757*
X03004Y03762*
X02999Y03766*
X02993Y03767*
G37*
G36*
X06294Y03717D02*
X06288Y03716D01*
X06283Y03712*
X06279Y03707*
X06278Y03701*
X06279Y03694*
X06283Y03689*
X06288Y03685*
X06294Y03684*
X06301Y03685*
X06306Y03689*
X06309Y03694*
X06311Y03701*
X06309Y03707*
X06306Y03712*
X06301Y03716*
X06294Y03717*
G37*
G36*
X01849D02*
X01843Y03716D01*
X01838Y03712*
X01834Y03707*
X01833Y03701*
X01834Y03694*
X01838Y03689*
X01843Y03685*
X01849Y03684*
X01856Y03685*
X01861Y03689*
X01864Y03694*
X01866Y03701*
X01864Y03707*
X01861Y03712*
X01856Y03716*
X01849Y03717*
G37*
G36*
X04437Y03677D02*
X0443Y03676D01*
X04425Y03672*
X04421Y03667*
X0442Y03661*
X04421Y03655*
X04425Y03649*
X0443Y03646*
X04437Y03645*
X04443Y03646*
X04448Y03649*
X04452Y03655*
X04453Y03661*
X04452Y03667*
X04448Y03672*
X04443Y03676*
X04437Y03677*
G37*
G36*
X04385D02*
X04379Y03676D01*
X04374Y03672*
X0437Y03667*
X04369Y03661*
X0437Y03655*
X04374Y03649*
X04379Y03646*
X04385Y03645*
X04392Y03646*
X04397Y03649*
X044Y03655*
X04402Y03661*
X044Y03667*
X04397Y03672*
X04392Y03676*
X04385Y03677*
G37*
G36*
X02679Y03677D02*
X02673Y03676D01*
X02668Y03672*
X02664Y03667*
X02663Y03661*
X02664Y03654*
X02668Y03649*
X02673Y03645*
X02679Y03644*
X02686Y03645*
X02691Y03649*
X02694Y03654*
X02696Y03661*
X02694Y03667*
X02691Y03672*
X02686Y03676*
X02679Y03677*
G37*
G36*
X01754D02*
X01748Y03676D01*
X01743Y03672*
X01739Y03667*
X01738Y03661*
X01739Y03654*
X01743Y03649*
X01748Y03645*
X01754Y03644*
X01761Y03645*
X01766Y03649*
X01769Y03654*
X01771Y03661*
X01769Y03667*
X01766Y03672*
X01761Y03676*
X01754Y03677*
G37*
G36*
X04053Y03657D02*
X04047Y03656D01*
X04042Y03652*
X04038Y03647*
X04037Y03641*
X04038Y03635*
X04042Y03629*
X04047Y03626*
X04053Y03625*
X0406Y03626*
X04065Y03629*
X04068Y03635*
X0407Y03641*
X04068Y03647*
X04065Y03652*
X0406Y03656*
X04053Y03657*
G37*
G36*
X03424Y03652D02*
X03418Y03651D01*
X03413Y03647*
X03409Y03642*
X03408Y03636*
X03409Y03629*
X03413Y03624*
X03418Y0362*
X03424Y03619*
X03431Y0362*
X03436Y03624*
X03439Y03629*
X03441Y03636*
X03439Y03642*
X03436Y03647*
X03431Y03651*
X03424Y03652*
G37*
G36*
X02799Y03632D02*
X02793Y03631D01*
X02788Y03627*
X02784Y03622*
X02783Y03616*
X02784Y03609*
X02788Y03604*
X02793Y036*
X02799Y03599*
X02806Y036*
X02811Y03604*
X02814Y03609*
X02816Y03616*
X02814Y03622*
X02811Y03627*
X02806Y03631*
X02799Y03632*
G37*
G36*
X02139Y03627D02*
X02133Y03626D01*
X02128Y03622*
X02124Y03617*
X02123Y03611*
X02124Y03604*
X02128Y03599*
X02133Y03595*
X02139Y03594*
X02146Y03595*
X02151Y03599*
X02154Y03604*
X02156Y03611*
X02154Y03617*
X02151Y03622*
X02146Y03626*
X02139Y03627*
G37*
G36*
X01884Y03617D02*
X01878Y03616D01*
X01873Y03612*
X01869Y03607*
X01868Y03601*
X01869Y03594*
X01873Y03589*
X01878Y03585*
X01884Y03584*
X01891Y03585*
X01896Y03589*
X01899Y03594*
X01901Y03601*
X01899Y03607*
X01896Y03612*
X01891Y03616*
X01884Y03617*
G37*
G36*
X03239Y03612D02*
X03233Y03611D01*
X03228Y03607*
X03224Y03602*
X03223Y03596*
X03224Y03589*
X03228Y03584*
X03233Y0358*
X03239Y03579*
X03246Y0358*
X03251Y03584*
X03254Y03589*
X03256Y03596*
X03254Y03602*
X03251Y03607*
X03246Y03611*
X03239Y03612*
G37*
G36*
X01549Y03637D02*
X01543Y03636D01*
X01538Y03632*
X01534Y03627*
X01533Y03621*
X01534Y03614*
X01538Y03609*
X01543Y03605*
X01549Y03604*
X01556Y03605*
X01556Y03606*
X01559Y03602*
X01559Y03602*
X01558Y03596*
X01559Y03589*
X01563Y03584*
X01568Y0358*
X01574Y03579*
X01581Y0358*
X01586Y03584*
X01589Y03589*
X01591Y03596*
X01589Y03602*
X01586Y03607*
X01581Y03611*
X01574Y03612*
X01568Y03611*
X01568Y0361*
X01564Y03614*
X01564Y03614*
X01566Y03621*
X01564Y03627*
X01561Y03632*
X01556Y03636*
X01549Y03637*
G37*
G36*
X02422Y03624D02*
X02413Y03623D01*
X02405Y03617*
X024Y0361*
X02398Y03601*
X024Y03592*
X02405Y03584*
X02413Y03579*
X02422Y03577*
X02431Y03579*
X02438Y03584*
X02443Y03592*
X02445Y03601*
X02443Y0361*
X02438Y03617*
X02431Y03623*
X02422Y03624*
G37*
G36*
X02774Y03582D02*
X02768Y03581D01*
X02763Y03577*
X02759Y03572*
X02758Y03566*
X02759Y03559*
X02763Y03554*
X02768Y0355*
X02774Y03549*
X02781Y0355*
X02786Y03554*
X02789Y03559*
X02791Y03566*
X02789Y03572*
X02786Y03577*
X02781Y03581*
X02774Y03582*
G37*
G36*
X0144Y03573D02*
X01434Y03572D01*
X01429Y03568*
X01425Y03563*
X01424Y03557*
X01425Y0355*
X01429Y03545*
X01434Y03541*
X0144Y0354*
X01447Y03541*
X01452Y03545*
X01455Y0355*
X01457Y03557*
X01455Y03563*
X01452Y03568*
X01447Y03572*
X0144Y03573*
G37*
G36*
X05964Y03579D02*
X05955Y03577D01*
X05947Y03572*
X05941Y03564*
X0594Y03555*
X05941Y03545*
X05947Y03537*
X05955Y03532*
X05964Y0353*
X05973Y03532*
X05981Y03537*
X05987Y03545*
X05989Y03555*
X05987Y03564*
X05981Y03572*
X05973Y03577*
X05964Y03579*
G37*
G36*
X02434Y03562D02*
X02428Y03561D01*
X02423Y03557*
X02419Y03552*
X02418Y03546*
X02419Y03539*
X02423Y03534*
X02428Y0353*
X02434Y03529*
X02441Y0353*
X02446Y03534*
X02449Y03539*
X02451Y03546*
X02449Y03552*
X02446Y03557*
X02441Y03561*
X02434Y03562*
G37*
G36*
X02254Y03552D02*
X02248Y03551D01*
X02243Y03547*
X02239Y03542*
X02238Y03536*
X02239Y03529*
X02243Y03524*
X02248Y0352*
X02254Y03519*
X02261Y0352*
X02266Y03524*
X02269Y03529*
X02271Y03536*
X02269Y03542*
X02266Y03547*
X02261Y03551*
X02254Y03552*
G37*
G36*
X05274Y03527D02*
X05268Y03526D01*
X05263Y03522*
X05259Y03517*
X05258Y03511*
X05259Y03504*
X05263Y03499*
X05268Y03495*
X05274Y03494*
X05281Y03495*
X05286Y03499*
X05289Y03504*
X05291Y03511*
X05289Y03517*
X05286Y03522*
X05281Y03526*
X05274Y03527*
G37*
G36*
X04318Y03524D02*
X04312Y03522D01*
X04307Y03519*
X04303Y03514*
X04302Y03507*
X04303Y03501*
X04307Y03496*
X04312Y03492*
X04318Y03491*
X04325Y03492*
X0433Y03496*
X04333Y03501*
X04335Y03507*
X04333Y03514*
X0433Y03519*
X04325Y03522*
X04318Y03524*
G37*
G36*
X03622Y03502D02*
X03616Y03501D01*
X03611Y03497*
X03607Y03492*
X03606Y03486*
X03607Y03479*
X03611Y03474*
X03616Y0347*
X03622Y03469*
X03629Y0347*
X03634Y03474*
X03637Y03479*
X03639Y03486*
X03637Y03492*
X03634Y03497*
X03629Y03501*
X03622Y03502*
G37*
G36*
X02579D02*
X02573Y03501D01*
X02568Y03497*
X02564Y03492*
X02563Y03486*
X02564Y03479*
X02568Y03474*
X02573Y0347*
X02579Y03469*
X02586Y0347*
X02591Y03474*
X02594Y03479*
X02596Y03486*
X02594Y03492*
X02591Y03497*
X02586Y03501*
X02579Y03502*
G37*
G36*
X02389Y03497D02*
X02383Y03496D01*
X02378Y03492*
X02374Y03487*
X02373Y03481*
X02374Y03474*
X02378Y03469*
X02383Y03465*
X02389Y03464*
X02396Y03465*
X02401Y03469*
X02404Y03474*
X02406Y03481*
X02404Y03487*
X02401Y03492*
X02396Y03496*
X02389Y03497*
G37*
G36*
X03437Y03492D02*
X0343Y03491D01*
X03425Y03487*
X03421Y03482*
X0342Y03476*
X03421Y0347*
X03425Y03464*
X0343Y03461*
X03437Y0346*
X03443Y03461*
X03448Y03464*
X03452Y0347*
X03453Y03476*
X03452Y03482*
X03448Y03487*
X03443Y03491*
X03437Y03492*
G37*
G36*
X06509Y03472D02*
X06503Y03471D01*
X06498Y03467*
X06494Y03462*
X06493Y03456*
X06494Y03449*
X06498Y03444*
X06503Y0344*
X06509Y03439*
X06516Y0344*
X06521Y03444*
X06524Y03449*
X06526Y03456*
X06524Y03462*
X06521Y03467*
X06516Y03471*
X06509Y03472*
G37*
G36*
X03469D02*
X03463Y03471D01*
X03458Y03467*
X03454Y03462*
X03453Y03456*
X03454Y03449*
X03458Y03444*
X03463Y0344*
X03469Y03439*
X03476Y0344*
X03481Y03444*
X03484Y03449*
X03486Y03456*
X03484Y03462*
X03481Y03467*
X03476Y03471*
X03469Y03472*
G37*
G36*
X03358Y03464D02*
X03352Y03463D01*
X03347Y03459*
X03343Y03454*
X03342Y03448*
X03343Y03441*
X03347Y03436*
X03352Y03432*
X03358Y03431*
X03365Y03432*
X0337Y03436*
X03373Y03441*
X03374Y03443*
X03379*
X03379Y0344*
X03383Y03435*
X03388Y03431*
X03394Y0343*
X03401Y03431*
X03406Y03435*
X03409Y0344*
X03411Y03447*
X03409Y03453*
X03406Y03458*
X03401Y03462*
X03394Y03463*
X03388Y03462*
X03383Y03458*
X03379Y03453*
X03379Y03451*
X03374*
X03373Y03454*
X0337Y03459*
X03365Y03463*
X03358Y03464*
G37*
G36*
X02422Y03467D02*
X02413Y03465D01*
X02405Y0346*
X024Y03452*
X02398Y03443*
X024Y03434*
X02405Y03427*
X02413Y03422*
X02422Y0342*
X02431Y03422*
X02438Y03427*
X02443Y03434*
X02445Y03443*
X02443Y03452*
X02438Y0346*
X02431Y03465*
X02422Y03467*
G37*
G36*
X06479Y03442D02*
X06473Y03441D01*
X06468Y03437*
X06464Y03432*
X06463Y03426*
X06464Y03419*
X06468Y03414*
X06473Y0341*
X06479Y03409*
X06486Y0341*
X06491Y03414*
X06494Y03419*
X06496Y03426*
X06494Y03432*
X06491Y03437*
X06486Y03441*
X06479Y03442*
G37*
G36*
X02634Y03422D02*
X02628Y03421D01*
X02623Y03417*
X02619Y03412*
X02618Y03406*
X02619Y03399*
X02623Y03394*
X02628Y0339*
X02634Y03389*
X02641Y0339*
X02646Y03394*
X02649Y03399*
X02651Y03406*
X02649Y03412*
X02646Y03417*
X02641Y03421*
X02634Y03422*
G37*
G36*
X06447Y03412D02*
X06441Y03411D01*
X06436Y03407*
X06432Y03402*
X06431Y03396*
X06432Y03389*
X06436Y03384*
X06441Y0338*
X06447Y03379*
X06453Y0338*
X06459Y03384*
X06462Y03389*
X06463Y03396*
X06462Y03402*
X06459Y03407*
X06453Y03411*
X06447Y03412*
G37*
G36*
X0307Y0341D02*
X03064Y03408D01*
X03059Y03405*
X03055Y03399*
X03054Y03393*
X03055Y03387*
X03059Y03382*
X03064Y03378*
X0307Y03377*
X03077Y03378*
X03082Y03382*
X03085Y03387*
X03087Y03393*
X03085Y03399*
X03082Y03405*
X03077Y03408*
X0307Y0341*
G37*
G36*
X06409Y03387D02*
X06403Y03386D01*
X06398Y03382*
X06394Y03377*
X06393Y03371*
X06394Y03364*
X06398Y03359*
X06403Y03355*
X06409Y03354*
X06416Y03355*
X06421Y03359*
X06424Y03364*
X06426Y03371*
X06424Y03377*
X06421Y03382*
X06416Y03386*
X06409Y03387*
G37*
G36*
X04438Y0337D02*
X04432Y03369D01*
X04427Y03366*
X04423Y0336*
X04422Y03354*
X04423Y03348*
X04427Y03342*
X04432Y03339*
X04438Y03338*
X04445Y03339*
X0445Y03342*
X04454Y03348*
X04455Y03354*
X04454Y0336*
X0445Y03366*
X04445Y03369*
X04438Y0337*
G37*
G36*
X03302Y0336D02*
X03296Y03359D01*
X03291Y03355*
X03287Y0335*
X03286Y03344*
X03287Y03337*
X03291Y03332*
X03296Y03328*
X03302Y03327*
X03309Y03328*
X03314Y03332*
X03317Y03337*
X03319Y03344*
X03317Y0335*
X03314Y03355*
X03309Y03359*
X03302Y0336*
G37*
G36*
X06354Y03347D02*
X06348Y03346D01*
X06343Y03342*
X06339Y03337*
X06338Y03331*
X06339Y03324*
X06343Y03319*
X06348Y03316*
X06354Y03314*
X0636Y03316*
X06366Y03319*
X06369Y03324*
X06371Y03331*
X06369Y03337*
X06366Y03342*
X0636Y03346*
X06354Y03347*
G37*
G36*
X03542Y03334D02*
X03536Y03333D01*
X03531Y0333*
X03527Y03324*
X03526Y03318*
X03527Y03312*
X03531Y03307*
X03536Y03303*
X03542Y03302*
X03549Y03303*
X03554Y03307*
X03557Y03312*
X03559Y03318*
X03557Y03324*
X03554Y0333*
X03549Y03333*
X03542Y03334*
G37*
G36*
X03263Y0332D02*
X03257Y03318D01*
X03252Y03315*
X03248Y0331*
X03247Y03303*
X03248Y03297*
X03252Y03292*
X03257Y03288*
X03263Y03287*
X03269Y03288*
X03275Y03292*
X03278Y03297*
X0328Y03303*
X03278Y0331*
X03275Y03315*
X03269Y03318*
X03263Y0332*
G37*
G36*
X03491Y03313D02*
X03485Y03312D01*
X0348Y03308*
X03476Y03303*
X03475Y03297*
X03476Y0329*
X0348Y03285*
X03485Y03281*
X03491Y0328*
X03498Y03281*
X03503Y03285*
X03506Y0329*
X03508Y03297*
X03506Y03303*
X03503Y03308*
X03498Y03312*
X03491Y03313*
G37*
G36*
X03657Y03312D02*
X03651Y03311D01*
X03646Y03307*
X03642Y03302*
X03641Y03296*
X03642Y0329*
X03646Y03284*
X03651Y03281*
X03657Y0328*
X03664Y03281*
X03669Y03284*
X03672Y0329*
X03674Y03296*
X03672Y03302*
X03669Y03307*
X03664Y03311*
X03657Y03312*
G37*
G36*
X06444Y03307D02*
X06438Y03306D01*
X06433Y03302*
X06429Y03297*
X06428Y03291*
X06429Y03284*
X06433Y03279*
X06438Y03275*
X06444Y03274*
X06451Y03275*
X06456Y03279*
X06459Y03284*
X06461Y03291*
X06459Y03297*
X06456Y03302*
X06451Y03306*
X06444Y03307*
G37*
G36*
X0259Y03304D02*
X02584Y03303D01*
X02579Y03299*
X02575Y03294*
X02574Y03288*
X02575Y03281*
X02579Y03276*
X02584Y03272*
X0259Y03271*
X02597Y03272*
X02602Y03276*
X02605Y03281*
X02607Y03288*
X02605Y03294*
X02602Y03299*
X02597Y03303*
X0259Y03304*
G37*
G36*
X03374Y03289D02*
X03368Y03288D01*
X03363Y03284*
X03359Y03279*
X03358Y03273*
X03359Y03266*
X03363Y03261*
X03368Y03257*
X03374Y03256*
X03381Y03257*
X03386Y03261*
X03389Y03266*
X03391Y03273*
X03389Y03279*
X03386Y03284*
X03381Y03288*
X03374Y03289*
G37*
G36*
X06334Y03282D02*
X06328Y03281D01*
X06323Y03277*
X06319Y03272*
X06318Y03266*
X06319Y03259*
X06323Y03254*
X06328Y0325*
X06334Y03249*
X06341Y0325*
X06346Y03254*
X06349Y03259*
X06351Y03266*
X06349Y03272*
X06346Y03277*
X06341Y03281*
X06334Y03282*
G37*
G36*
X03744Y03277D02*
X03738Y03276D01*
X03733Y03272*
X03729Y03267*
X03728Y03261*
X03729Y03254*
X03733Y03249*
X03738Y03245*
X03744Y03244*
X03751Y03245*
X03756Y03249*
X03759Y03254*
X03761Y03261*
X03759Y03267*
X03756Y03272*
X03751Y03276*
X03744Y03277*
G37*
G36*
X02259D02*
X02253Y03276D01*
X02248Y03272*
X02244Y03267*
X02243Y03261*
X02244Y03254*
X02248Y03249*
X02253Y03245*
X02259Y03244*
X02266Y03245*
X02271Y03249*
X02274Y03254*
X02276Y03261*
X02274Y03267*
X02271Y03272*
X02266Y03276*
X02259Y03277*
G37*
G36*
X0323Y03251D02*
X03224Y0325D01*
X03219Y03246*
X03215Y03241*
X03214Y03235*
X03215Y03228*
X03219Y03223*
X03224Y03219*
X0323Y03218*
X03237Y03219*
X03242Y03223*
X03245Y03228*
X03247Y03235*
X03245Y03241*
X03242Y03246*
X03237Y0325*
X0323Y03251*
G37*
G36*
X03806D02*
X038Y0325D01*
X03795Y03246*
X03791Y03241*
X0379Y03235*
X03791Y03228*
X03795Y03223*
X03797Y03222*
X03796Y03216*
X03793Y03216*
X03788Y03212*
X03784Y03207*
X03783Y03201*
X03784Y03194*
X03788Y03189*
X03793Y03185*
X03799Y03184*
X03806Y03185*
X03811Y03189*
X03814Y03194*
X03816Y03201*
X03814Y03207*
X03811Y03212*
X03809Y03214*
X0381Y03219*
X03813Y03219*
X03818Y03223*
X03821Y03228*
X03823Y03235*
X03821Y03241*
X03818Y03246*
X03813Y0325*
X03806Y03251*
G37*
G36*
X02205Y03216D02*
X02199Y03215D01*
X02194Y03211*
X0219Y03206*
X02189Y032*
X0219Y03193*
X02194Y03188*
X02199Y03184*
X02205Y03183*
X02212Y03184*
X02217Y03188*
X0222Y03193*
X02222Y032*
X0222Y03206*
X02217Y03211*
X02212Y03215*
X02205Y03216*
G37*
G36*
X02422Y03263D02*
X02413Y03261D01*
X02405Y03256*
X024Y03248*
X02398Y03239*
X024Y0323*
X02405Y03223*
X02409Y0322*
X02408Y03215*
X02407Y03214*
X02402Y03211*
X02398Y03206*
X02397Y03199*
X02398Y03193*
X02402Y03188*
X02407Y03184*
X02414Y03183*
X0242Y03184*
X02425Y03188*
X02429Y03193*
X0243Y03199*
X02429Y03206*
X02425Y03211*
X02425Y03211*
X02426Y03217*
X02431Y03218*
X02438Y03223*
X02443Y0323*
X02445Y03239*
X02443Y03248*
X02438Y03256*
X02431Y03261*
X02422Y03263*
G37*
G36*
X06262Y03236D02*
X06256Y03235D01*
X06251Y03231*
X06247Y03226*
X06246Y0322*
X06247Y03213*
X06251Y03208*
X06256Y03204*
X06262Y03203*
X06269Y03204*
X06269Y03205*
X06272Y03201*
X06272Y03201*
X06271Y03195*
X06272Y03188*
X06276Y03183*
X06281Y03179*
X06287Y03178*
X06294Y03179*
X06299Y03183*
X06302Y03188*
X06304Y03195*
X06302Y03201*
X06299Y03206*
X06294Y0321*
X06287Y03211*
X06281Y0321*
X06281Y03209*
X06277Y03213*
X06277Y03213*
X06279Y0322*
X06277Y03226*
X06274Y03231*
X06269Y03235*
X06262Y03236*
G37*
G36*
X06439Y03207D02*
X06433Y03206D01*
X06428Y03202*
X06424Y03197*
X06423Y03191*
X06424Y03184*
X06428Y03179*
X06433Y03175*
X06439Y03174*
X06446Y03175*
X06451Y03179*
X06454Y03184*
X06456Y03191*
X06454Y03197*
X06451Y03202*
X06446Y03206*
X06439Y03207*
G37*
G36*
X03188Y03203D02*
X03182Y03202D01*
X03177Y03198*
X03173Y03193*
X03172Y03187*
X03173Y0318*
X03177Y03175*
X03182Y03171*
X03188Y0317*
X03195Y03171*
X032Y03175*
X03204Y0318*
X03205Y03187*
X03204Y03193*
X032Y03198*
X03195Y03202*
X03188Y03203*
G37*
G36*
X02591Y03202D02*
X02585Y03201D01*
X0258Y03197*
X02576Y03192*
X02575Y03186*
X02576Y03179*
X0258Y03174*
X02585Y03171*
X02591Y03169*
X02598Y03171*
X02603Y03174*
X02606Y03179*
X02608Y03186*
X02606Y03192*
X02603Y03197*
X02598Y03201*
X02591Y03202*
G37*
G36*
X02462Y03188D02*
X02456Y03187D01*
X0245Y03183*
X02447Y03178*
X02446Y03172*
X02447Y03166*
X0245Y0316*
X02456Y03157*
X02462Y03155*
X02468Y03157*
X02473Y0316*
X02477Y03166*
X02478Y03172*
X02477Y03178*
X02473Y03183*
X02468Y03187*
X02462Y03188*
G37*
G36*
X03829Y03192D02*
X03823Y03191D01*
X03818Y03187*
X03814Y03182*
X03813Y03176*
X03814Y03169*
X03818Y03164*
X03823Y0316*
X03829Y03159*
X03836Y0316*
X03836Y03161*
X03839Y03157*
X03839Y03157*
X03838Y03151*
X03839Y03144*
X03843Y03139*
X03848Y03135*
X03854Y03134*
X03861Y03135*
X03866Y03139*
X03869Y03144*
X03871Y03151*
X03869Y03157*
X03866Y03162*
X03861Y03166*
X03854Y03167*
X03848Y03166*
X03848Y03165*
X03844Y03169*
X03844Y03169*
X03846Y03176*
X03844Y03182*
X03841Y03187*
X03836Y03191*
X03829Y03192*
G37*
G36*
X06335Y03163D02*
X06329Y03162D01*
X06324Y03158*
X0632Y03153*
X06319Y03147*
X0632Y0314*
X06324Y03135*
X06329Y03132*
X06335Y0313*
X06342Y03132*
X06347Y03135*
X0635Y0314*
X06352Y03147*
X0635Y03153*
X06347Y03158*
X06342Y03162*
X06335Y03163*
G37*
G36*
X01459D02*
X01453Y03162D01*
X01448Y03158*
X01444Y03153*
X01443Y03147*
X01444Y0314*
X01448Y03135*
X01453Y03131*
X01459Y0313*
X01466Y03131*
X01471Y03135*
X01474Y0314*
X01476Y03147*
X01474Y03153*
X01471Y03158*
X01466Y03162*
X01459Y03163*
G37*
G36*
X03275Y03158D02*
X03269Y03156D01*
X03264Y03153*
X0326Y03147*
X03259Y03141*
X0326Y03135*
X03264Y0313*
X03269Y03126*
X03275Y03125*
X03281Y03126*
X03287Y0313*
X0329Y03135*
X03291Y03141*
X0329Y03147*
X03287Y03153*
X03281Y03156*
X03275Y03158*
G37*
G36*
X06304Y03137D02*
X06298Y03136D01*
X06293Y03132*
X06289Y03127*
X06288Y03121*
X06289Y03114*
X06293Y03109*
X06298Y03105*
X06304Y03104*
X06311Y03105*
X06316Y03109*
X06319Y03114*
X06321Y03121*
X06319Y03127*
X06316Y03132*
X06311Y03136*
X06304Y03137*
G37*
G36*
X03939D02*
X03933Y03136D01*
X03928Y03132*
X03924Y03127*
X03923Y03121*
X03924Y03114*
X03928Y03109*
X03933Y03105*
X03939Y03104*
X03946Y03105*
X03951Y03109*
X03954Y03114*
X03956Y03121*
X03954Y03127*
X03951Y03132*
X03946Y03136*
X03939Y03137*
G37*
G36*
X03491Y03119D02*
X03485Y03118D01*
X0348Y03114*
X03476Y03109*
X03475Y03103*
X03476Y03096*
X0348Y03091*
X03485Y03087*
X03491Y03086*
X03498Y03087*
X03503Y03091*
X03506Y03096*
X03508Y03103*
X03506Y03109*
X03503Y03114*
X03498Y03118*
X03491Y03119*
G37*
G36*
X02418Y03134D02*
X02412Y03133D01*
X02407Y0313*
X02403Y03124*
X02402Y03118*
X02403Y03112*
X02407Y03106*
X02408Y03106*
Y031*
X02405Y03098*
X024Y03091*
X02398Y03082*
X024Y03073*
X02405Y03065*
X02413Y0306*
X02422Y03058*
X02431Y0306*
X02438Y03065*
X02443Y03073*
X02445Y03082*
X02443Y03091*
X02438Y03098*
X02432Y03102*
X02431Y03105*
X02431Y03108*
X02433Y03112*
X02435Y03118*
X02433Y03124*
X0243Y0313*
X02424Y03133*
X02418Y03134*
G37*
G36*
X03368Y03066D02*
X03362Y03065D01*
X03357Y03061*
X03353Y03056*
X03352Y0305*
X03353Y03043*
X03357Y03038*
X03362Y03034*
X03368Y03033*
X03375Y03034*
X0338Y03038*
X03383Y03043*
X03385Y0305*
X03383Y03056*
X0338Y03061*
X03375Y03065*
X03368Y03066*
G37*
G36*
X03344Y03012D02*
X03338Y03011D01*
X03333Y03007*
X03329Y03002*
X03328Y02996*
X03329Y02989*
X03333Y02984*
X03338Y0298*
X03344Y02979*
X03351Y0298*
X03356Y02984*
X03359Y02989*
X03361Y02996*
X03359Y03002*
X03356Y03007*
X03351Y03011*
X03344Y03012*
G37*
G36*
X03197Y02986D02*
X03191Y02985D01*
X03186Y02981*
X03182Y02976*
X03181Y0297*
X03182Y02963*
X03186Y02958*
X03191Y02954*
X03197Y02953*
X03204Y02954*
X03209Y02958*
X03212Y02963*
X03214Y0297*
X03212Y02976*
X03209Y02981*
X03204Y02985*
X03197Y02986*
G37*
G36*
X04794Y02824D02*
X04788Y02823D01*
X04782Y02819*
X04779Y02814*
X04777Y02808*
X04779Y02801*
X04782Y02796*
X04788Y02793*
X04794Y02791*
X048Y02793*
X04805Y02796*
X04809Y02801*
X0481Y02808*
X04809Y02814*
X04805Y02819*
X048Y02823*
X04794Y02824*
G37*
G36*
X04503Y02806D02*
X04497Y02804D01*
X04492Y02801*
X04488Y02796*
X04487Y02789*
X04488Y02783*
X04492Y02778*
X04497Y02774*
X04503Y02773*
X04509Y02774*
X04515Y02778*
X04518Y02783*
X04519Y02789*
X04518Y02796*
X04515Y02801*
X04509Y02804*
X04503Y02806*
G37*
G36*
X02146Y02769D02*
X0214Y02768D01*
X02135Y02764*
X02131Y02759*
X0213Y02753*
X02131Y02746*
X02135Y02741*
X0214Y02737*
X02146Y02736*
X02153Y02737*
X02158Y02741*
X02161Y02746*
X02163Y02753*
X02161Y02759*
X02158Y02764*
X02153Y02768*
X02146Y02769*
G37*
G36*
X02692Y02737D02*
X02686Y02736D01*
X02681Y02732*
X02677Y02727*
X02676Y02721*
X02677Y02715*
X02681Y02709*
X02686Y02706*
X02692Y02705*
X02699Y02706*
X02704Y02709*
X02707Y02715*
X02709Y02721*
X02707Y02727*
X02704Y02732*
X02699Y02736*
X02692Y02737*
G37*
G36*
X02394Y02736D02*
X02388Y02735D01*
X02383Y02732*
X02379Y02726*
X02378Y0272*
X02379Y02714*
X02383Y02708*
X02388Y02705*
X02394Y02704*
X024Y02705*
X02406Y02708*
X02409Y02714*
X02411Y0272*
X02409Y02726*
X02406Y02732*
X024Y02735*
X02394Y02736*
G37*
G36*
X02494Y02712D02*
X02488Y02711D01*
X02483Y02707*
X02479Y02702*
X02478Y02696*
X02479Y02689*
X02483Y02684*
X02488Y02681*
X02488Y02679*
Y02678*
X02488Y02675*
X02483Y02672*
X02479Y02667*
X02478Y02661*
X02479Y02654*
X02483Y02649*
X02488Y02645*
X02494Y02644*
X02501Y02645*
X02506Y02649*
X02509Y02654*
X02511Y02661*
X02509Y02667*
X02506Y02672*
X02501Y02675*
X02501Y02678*
Y02679*
X02501Y02681*
X02506Y02684*
X02509Y02689*
X02511Y02696*
X02509Y02702*
X02506Y02707*
X02501Y02711*
X02494Y02712*
G37*
G36*
X02958Y02637D02*
X02952Y02636D01*
X02947Y02632*
X02943Y02627*
X02942Y02621*
X02943Y02614*
X02947Y02609*
X02952Y02605*
X02958Y02604*
X02965Y02605*
X0297Y02609*
X02973Y02614*
X02975Y02621*
X02973Y02627*
X0297Y02632*
X02965Y02636*
X02958Y02637*
G37*
G36*
X02429D02*
X02422Y02636D01*
X02417Y02632*
X02414Y02627*
X02412Y02621*
X02414Y02614*
X02417Y02609*
X02422Y02605*
X02429Y02604*
X02435Y02605*
X0244Y02609*
X02444Y02614*
X02445Y02621*
X02444Y02627*
X0244Y02632*
X02435Y02636*
X02429Y02637*
G37*
G36*
X02252Y02629D02*
X02246Y02628D01*
X0224Y02625*
X02237Y02619*
X02236Y02613*
X02237Y02607*
X0224Y02602*
X02246Y02598*
X02252Y02597*
X02258Y02598*
X02263Y02602*
X02267Y02607*
X02268Y02613*
X02267Y02619*
X02263Y02625*
X02258Y02628*
X02252Y02629*
G37*
G36*
X02821Y02617D02*
X02815Y02616D01*
X0281Y02612*
X02806Y02607*
X02805Y02601*
X02806Y02594*
X0281Y02589*
X02815Y02585*
X02821Y02584*
X02828Y02585*
X02833Y02589*
X02836Y02594*
X02838Y02601*
X02836Y02607*
X02833Y02612*
X02828Y02616*
X02821Y02617*
G37*
G36*
X03623Y02603D02*
X03617Y02602D01*
X03612Y02598*
X03608Y02593*
X03607Y02587*
X03608Y0258*
X03612Y02575*
X03617Y02571*
X03623Y0257*
X0363Y02571*
X03635Y02575*
X03638Y0258*
X0364Y02587*
X03638Y02593*
X03635Y02598*
X0363Y02602*
X03623Y02603*
G37*
G36*
X04298Y02641D02*
X04286Y02639D01*
X04275Y02635*
X04266Y02627*
X04258Y02618*
X04254Y02607*
X04252Y02595*
X04254Y02583*
X04258Y02572*
X04266Y02562*
X04275Y02555*
X04286Y02551*
X04298Y02549*
X0431Y02551*
X04321Y02555*
X04331Y02562*
X04338Y02572*
X04342Y02583*
X04344Y02595*
X04342Y02607*
X04338Y02618*
X04331Y02627*
X04321Y02635*
X0431Y02639*
X04298Y02641*
G37*
G36*
X0418D02*
X04168Y02639D01*
X04157Y02635*
X04148Y02627*
X0414Y02618*
X04136Y02607*
X04134Y02595*
X04136Y02583*
X0414Y02572*
X04148Y02562*
X04157Y02555*
X04168Y02551*
X0418Y02549*
X04192Y02551*
X04203Y02555*
X04212Y02562*
X0422Y02572*
X04224Y02583*
X04226Y02595*
X04224Y02607*
X0422Y02618*
X04212Y02627*
X04203Y02635*
X04192Y02639*
X0418Y02641*
G37*
G36*
X04062D02*
X0405Y02639D01*
X04039Y02635*
X04029Y02627*
X04022Y02618*
X04018Y02607*
X04016Y02595*
X04018Y02583*
X04022Y02572*
X04029Y02562*
X04039Y02555*
X0405Y02551*
X04062Y02549*
X04074Y02551*
X04085Y02555*
X04094Y02562*
X04102Y02572*
X04106Y02583*
X04108Y02595*
X04106Y02607*
X04102Y02618*
X04094Y02627*
X04085Y02635*
X04074Y02639*
X04062Y02641*
G37*
G36*
X0102Y02497D02*
X01014Y02496D01*
X01009Y02492*
X01005Y02487*
X01004Y02481*
X01005Y02474*
X01009Y02469*
X01014Y02465*
X0102Y02464*
X01027Y02465*
X01032Y02469*
X01035Y02474*
X01037Y02481*
X01035Y02487*
X01032Y02492*
X01027Y02496*
X0102Y02497*
G37*
G36*
X06196Y02508D02*
X06187Y02506D01*
X06179Y02501*
X06174Y02493*
X06172Y02484*
X06174Y02474*
X06179Y02466*
X06187Y02461*
X06196Y02459*
X06206Y02461*
X06214Y02466*
X06219Y02474*
X06221Y02484*
X06219Y02493*
X06214Y02501*
X06206Y02506*
X06196Y02508*
G37*
G36*
X02624Y02477D02*
X02618Y02476D01*
X02613Y02472*
X02609Y02467*
X02608Y02461*
X02609Y02454*
X02609Y02454*
X02606Y0245*
X02606Y02451*
X02599Y02452*
X02593Y02451*
X02588Y02447*
X02584Y02442*
X02583Y02436*
X02584Y02431*
X02583Y0243*
X02581Y02427*
X0258Y02427*
X02575Y02428*
X02569Y02427*
X02564Y02423*
X0256Y02418*
X02559Y02412*
X0256Y02405*
X02564Y024*
X02569Y02396*
X02575Y02395*
X02582Y02396*
X02587Y024*
X0259Y02405*
X02592Y02412*
X02591Y02416*
X02591Y02417*
X02594Y0242*
X02595Y0242*
X02599Y02419*
X02606Y0242*
X02611Y02424*
X02614Y02429*
X02616Y02436*
X02614Y02442*
X02614Y02442*
X02618Y02446*
X02618Y02445*
X02624Y02444*
X02631Y02445*
X02636Y02449*
X02639Y02454*
X02641Y02461*
X02639Y02467*
X02636Y02472*
X02631Y02476*
X02624Y02477*
G37*
G36*
X02272Y0248D02*
X02265Y02478D01*
X0226Y02475*
X02256Y0247*
X02255Y02463*
X02256Y02457*
X0226Y02452*
X02265Y02448*
X02272Y02447*
X02278Y02448*
X02283Y02452*
X02287Y02457*
X02288Y02463*
X02287Y0247*
X02283Y02475*
X02278Y02478*
X02272Y0248*
G37*
G36*
X02525Y02479D02*
X02519Y02478D01*
X02514Y02474*
X0251Y02469*
X02509Y02463*
X0251Y02456*
X02514Y02451*
X02519Y02447*
X02525Y02446*
X02532Y02447*
X02537Y02451*
X0254Y02456*
X02542Y02463*
X0254Y02469*
X02537Y02474*
X02532Y02478*
X02525Y02479*
G37*
G36*
X05578Y02534D02*
X05566Y02533D01*
X05555Y02528*
X05545Y02521*
X05538Y02511*
X05533Y025*
X05532Y02489*
X05533Y02477*
X05538Y02466*
X05545Y02456*
X05555Y02449*
X05566Y02444*
X05578Y02443*
X0559Y02444*
X05601Y02449*
X0561Y02456*
X05617Y02466*
X05622Y02477*
X05624Y02489*
X05622Y025*
X05617Y02511*
X0561Y02521*
X05601Y02528*
X0559Y02533*
X05578Y02534*
G37*
G36*
X02948Y02472D02*
X02942Y02471D01*
X02936Y02468*
X02933Y02462*
X02931Y02456*
X02933Y0245*
X02936Y02444*
X02942Y02441*
X02948Y0244*
X02954Y02441*
X02959Y02444*
X02963Y0245*
X02964Y02456*
X02963Y02462*
X02959Y02468*
X02954Y02471*
X02948Y02472*
G37*
G36*
X0299Y02456D02*
X02982Y02455D01*
X02976Y02451*
X02972Y02444*
X0297Y02437*
X02972Y0243*
X02976Y02424*
X02982Y02419*
X0299Y02418*
X02997Y02419*
X03003Y02424*
X03007Y0243*
X03009Y02437*
X03007Y02444*
X03003Y02451*
X02997Y02455*
X0299Y02456*
G37*
G36*
X02202D02*
X02195Y02455D01*
X02189Y02451*
X02185Y02444*
X02183Y02437*
X02185Y0243*
X02189Y02424*
X02195Y02419*
X02202Y02418*
X0221Y02419*
X02216Y02424*
X0222Y0243*
X02221Y02437*
X0222Y02444*
X02216Y02451*
X0221Y02455*
X02202Y02456*
G37*
G36*
X03617Y02552D02*
X03604Y02551D01*
X03591Y02547*
X0358Y02541*
X03569Y02533*
X03561Y02522*
X03555Y02511*
X03551Y02498*
X0355Y02485*
X03551Y02472*
X03555Y02459*
X03561Y02447*
X03569Y02437*
X0358Y02429*
X03591Y02423*
X03604Y02419*
X03617Y02417*
X0363Y02419*
X03643Y02423*
X03654Y02429*
X03665Y02437*
X03673Y02447*
X03679Y02459*
X03683Y02472*
X03684Y02485*
X03683Y02498*
X03679Y02511*
X03673Y02522*
X03665Y02533*
X03654Y02541*
X03643Y02547*
X0363Y02551*
X03617Y02552*
G37*
G36*
X01651D02*
X01638Y02551D01*
X01625Y02547*
X01614Y02541*
X01603Y02533*
X01595Y02522*
X01589Y02511*
X01585Y02498*
X01584Y02485*
X01585Y02472*
X01589Y02459*
X01595Y02447*
X01603Y02437*
X01614Y02429*
X01625Y02423*
X01638Y02419*
X01651Y02417*
X01664Y02419*
X01677Y02423*
X01688Y02429*
X01699Y02437*
X01707Y02447*
X01713Y02459*
X01717Y02472*
X01718Y02485*
X01717Y02498*
X01713Y02511*
X01707Y02522*
X01699Y02533*
X01688Y02541*
X01677Y02547*
X01664Y02551*
X01651Y02552*
G37*
G36*
X00199Y02545D02*
X00187Y02544D01*
X00175Y0254*
X00164Y02534*
X00154Y02526*
X00146Y02516*
X0014Y02505*
X00136Y02493*
X00135Y02481*
X00136Y02468*
X0014Y02456*
X00146Y02445*
X00154Y02435*
X00164Y02427*
X00175Y02421*
X00187Y02417*
X00199Y02416*
X00212Y02417*
X00224Y02421*
X00235Y02427*
X00245Y02435*
X00253Y02445*
X00259Y02456*
X00262Y02468*
X00264Y02481*
X00262Y02493*
X00259Y02505*
X00253Y02516*
X00245Y02526*
X00235Y02534*
X00224Y0254*
X00212Y02544*
X00199Y02545*
G37*
G36*
X02894Y02447D02*
X02888Y02446D01*
X02883Y02442*
X02879Y02437*
X02878Y02431*
X02879Y02424*
X02883Y02419*
X02888Y02415*
X02894Y02414*
X02901Y02415*
X02906Y02419*
X02907*
X02909Y02416*
X02914Y02412*
X0292Y02411*
X02927Y02412*
X02932Y02416*
X02935Y02421*
X02937Y02428*
X02935Y02434*
X02932Y02439*
X02927Y02443*
X0292Y02444*
X02914Y02443*
X02909Y02439*
X02908*
X02906Y02442*
X02901Y02446*
X02894Y02447*
G37*
G36*
X04039Y02422D02*
X04033Y02421D01*
X04028Y02417*
X04024Y02412*
X04023Y02406*
X04024Y02399*
X04028Y02394*
X04033Y0239*
X04039Y02389*
X04046Y0239*
X04051Y02394*
X04054Y02399*
X04056Y02406*
X04054Y02412*
X04051Y02417*
X04046Y02421*
X04039Y02422*
G37*
G36*
X03498Y02357D02*
X03492Y02356D01*
X03487Y02352*
X03483Y02347*
X03482Y02341*
X03483Y02334*
X03487Y02329*
X03492Y02325*
X03498Y02324*
X03505Y02325*
X0351Y02329*
X03513Y02334*
X03515Y02341*
X03513Y02347*
X0351Y02352*
X03505Y02356*
X03498Y02357*
G37*
G36*
X02726Y02309D02*
X0272Y02308D01*
X02715Y02304*
X02713Y02301*
X02709Y02304*
X02702Y02305*
X02696Y02304*
X02691Y023*
X0269Y02299*
X02684Y02299*
X02682Y02302*
X02677Y02306*
X02671Y02307*
X02664Y02306*
X02659Y02302*
X02656Y02297*
X02654Y02291*
X02655Y02289*
X02654Y02288*
X0265Y02285*
X02645Y02286*
X02639Y02285*
X02634Y02281*
X0263Y02276*
X02629Y0227*
X0263Y02264*
X02634Y02258*
X02639Y02255*
X02645Y02254*
X02652Y02255*
X02657Y02258*
X0266Y02264*
X02662Y0227*
X02661Y02272*
X02662Y02273*
X02666Y02275*
X02671Y02274*
X02677Y02275*
X02682Y02279*
X02683Y0228*
X02689Y0228*
X02691Y02277*
X02696Y02273*
X02702Y02272*
X02709Y02273*
X02714Y02277*
X02716Y0228*
X0272Y02277*
X02726Y02276*
X02733Y02277*
X02738Y02281*
X02741Y02286*
X02743Y02293*
X02741Y02299*
X02738Y02304*
X02733Y02308*
X02726Y02309*
G37*
G36*
X02475Y02307D02*
X02469Y02306D01*
X02464Y02302*
X02462Y02299*
X02457Y02297*
X0245Y02298*
X02444Y02297*
X02439Y02293*
X02435Y02288*
X02434Y02282*
X02435Y02275*
X02439Y0227*
X02444Y02266*
X0245Y02265*
X02457Y02266*
X02462Y0227*
X02465Y02275*
X0247Y02275*
X02475Y02274*
X02482Y02275*
X02487Y02279*
X0249Y02284*
X02492Y02291*
X0249Y02297*
X02487Y02302*
X02482Y02306*
X02475Y02307*
G37*
G36*
X02803Y02323D02*
X02797Y02322D01*
X02792Y02318*
X02788Y02313*
X02787Y02307*
X02788Y023*
X02792Y02295*
X02797Y02291*
X02803Y0229*
X0281Y02291*
X02815Y02295*
X02818Y023*
X0282Y02307*
X02818Y02313*
X02815Y02318*
X0281Y02322*
X02803Y02323*
G37*
G36*
X02985Y02303D02*
X02979Y02302D01*
X02974Y02298*
X0297Y02293*
X02969Y02287*
X0297Y0228*
X02974Y02275*
X02979Y02271*
X02985Y0227*
X02992Y02271*
X02997Y02275*
X03Y0228*
X03002Y02287*
X03Y02293*
X02997Y02298*
X02992Y02302*
X02985Y02303*
G37*
G36*
X02942Y02302D02*
X02936Y02301D01*
X02931Y02297*
X02927Y02292*
X02926Y02286*
X02927Y02279*
X02931Y02274*
X02936Y0227*
X02942Y02269*
X02949Y0227*
X02954Y02274*
X02957Y02279*
X02959Y02286*
X02957Y02292*
X02954Y02297*
X02949Y02301*
X02942Y02302*
G37*
G36*
X05327Y02346D02*
X05317Y02345D01*
X05308Y02341*
X053Y02334*
X05294Y02326*
X0529Y02317*
X05288Y02307*
X0529Y02297*
X05294Y02288*
X053Y0228*
X05308Y02273*
X05317Y02269*
X05327Y02268*
X05337Y02269*
X05347Y02273*
X05355Y0228*
X05361Y02288*
X05365Y02297*
X05366Y02307*
X05365Y02317*
X05361Y02326*
X05355Y02334*
X05347Y02341*
X05337Y02345*
X05327Y02346*
G37*
G36*
X04927D02*
X04917Y02345D01*
X04908Y02341*
X049Y02334*
X04894Y02326*
X0489Y02317*
X04888Y02307*
X0489Y02297*
X04894Y02288*
X049Y0228*
X04908Y02273*
X04917Y02269*
X04927Y02268*
X04937Y02269*
X04947Y02273*
X04955Y0228*
X04961Y02288*
X04965Y02297*
X04966Y02307*
X04965Y02317*
X04961Y02326*
X04955Y02334*
X04947Y02341*
X04937Y02345*
X04927Y02346*
G37*
G36*
X04727D02*
X04717Y02345D01*
X04708Y02341*
X047Y02334*
X04694Y02326*
X0469Y02317*
X04688Y02307*
X0469Y02297*
X04694Y02288*
X047Y0228*
X04708Y02273*
X04717Y02269*
X04727Y02268*
X04737Y02269*
X04747Y02273*
X04755Y0228*
X04761Y02288*
X04765Y02297*
X04766Y02307*
X04765Y02317*
X04761Y02326*
X04755Y02334*
X04747Y02341*
X04737Y02345*
X04727Y02346*
G37*
G36*
X04327D02*
X04317Y02345D01*
X04308Y02341*
X043Y02334*
X04294Y02326*
X0429Y02317*
X04288Y02307*
X0429Y02297*
X04294Y02288*
X043Y0228*
X04308Y02273*
X04317Y02269*
X04327Y02268*
X04337Y02269*
X04347Y02273*
X04355Y0228*
X04361Y02288*
X04365Y02297*
X04366Y02307*
X04365Y02317*
X04361Y02326*
X04355Y02334*
X04347Y02341*
X04337Y02345*
X04327Y02346*
G37*
G36*
X02409Y0233D02*
X02403Y02329D01*
X02398Y02325*
X02394Y0232*
X02393Y02314*
X02394Y02307*
X02398Y02302*
X02399Y02301*
Y02295*
X02398Y02294*
X02394Y02289*
X02393Y02283*
X02394Y02276*
X02398Y02271*
X02403Y02267*
X02409Y02266*
X02416Y02267*
X02421Y02271*
X02424Y02276*
X02426Y02283*
X02424Y02289*
X02421Y02294*
X02419Y02295*
Y02301*
X02421Y02302*
X02424Y02307*
X02426Y02314*
X02424Y0232*
X02421Y02325*
X02416Y02329*
X02409Y0233*
G37*
G36*
X02579Y02297D02*
X02573Y02296D01*
X02568Y02292*
X02564Y02287*
X02563Y02281*
X02564Y02274*
X02568Y02269*
X02573Y02265*
X02579Y02264*
X02586Y02265*
X02591Y02269*
X02594Y02274*
X02596Y02281*
X02594Y02287*
X02591Y02292*
X02586Y02296*
X02579Y02297*
G37*
G36*
X03342Y02279D02*
X03336Y02278D01*
X03331Y02274*
X03327Y02269*
X03326Y02263*
X03327Y02256*
X03331Y02251*
X03336Y02247*
X03342Y02246*
X03349Y02247*
X03354Y02251*
X03357Y02256*
X03359Y02263*
X03357Y02269*
X03354Y02274*
X03349Y02278*
X03342Y02279*
G37*
G36*
X02841D02*
X02835Y02278D01*
X0283Y02274*
X02826Y02269*
X02825Y02263*
X02826Y02256*
X0283Y02251*
X02835Y02247*
X02841Y02246*
X02848Y02247*
X02853Y02251*
X02856Y02256*
X02858Y02263*
X02856Y02269*
X02853Y02274*
X02848Y02278*
X02841Y02279*
G37*
G36*
X00996Y02272D02*
X0099Y02271D01*
X00985Y02267*
X00981Y02262*
X0098Y02256*
X00981Y02249*
X00985Y02244*
X0099Y0224*
X00996Y02239*
X01003Y0224*
X01008Y02244*
X01011Y02249*
X01013Y02256*
X01011Y02262*
X01008Y02267*
X01003Y02271*
X00996Y02272*
G37*
G36*
X05634Y02252D02*
X05628Y02251D01*
X05623Y02247*
X05619Y02242*
X05618Y02236*
X05619Y02229*
X05623Y02224*
X05628Y0222*
X05634Y02219*
X05641Y0222*
X05646Y02224*
X05649Y02229*
X05651Y02236*
X05649Y02242*
X05646Y02247*
X05641Y02251*
X05634Y02252*
G37*
G36*
X02499D02*
X02493Y02251D01*
X02488Y02247*
X02484Y02242*
X02483Y02236*
X02484Y02229*
X02488Y02224*
X02493Y0222*
X02499Y02219*
X02506Y0222*
X02511Y02224*
X02514Y02229*
X02516Y02236*
X02514Y02242*
X02511Y02247*
X02506Y02251*
X02499Y02252*
G37*
G36*
X0233Y02231D02*
X02324Y0223D01*
X02319Y02226*
X02315Y02221*
X02314Y02215*
X02315Y02208*
X02319Y02203*
X02324Y02199*
X0233Y02198*
X02337Y02199*
X02342Y02203*
X02345Y02208*
X02347Y02215*
X02345Y02221*
X02342Y02226*
X02337Y0223*
X0233Y02231*
G37*
G36*
X05577Y0223D02*
X05571Y02229D01*
X05566Y02225*
X05562Y0222*
X05561Y02214*
X05562Y02207*
X05566Y02202*
X05571Y02198*
X05577Y02197*
X05584Y02198*
X05589Y02202*
X05592Y02207*
X05594Y02214*
X05592Y0222*
X05589Y02225*
X05584Y02229*
X05577Y0223*
G37*
G36*
X06424Y02197D02*
X06418Y02196D01*
X06413Y02192*
X06409Y02187*
X06408Y02181*
X06409Y02174*
X06413Y02169*
X06418Y02165*
X06424Y02164*
X06431Y02165*
X06436Y02169*
X06439Y02174*
X06441Y02181*
X06439Y02187*
X06436Y02192*
X06431Y02196*
X06424Y02197*
G37*
G36*
X01754Y02142D02*
X01748Y02141D01*
X01743Y02137*
X01739Y02132*
X01738Y02126*
X01739Y02119*
X01743Y02114*
X01748Y0211*
X01754Y02109*
X01761Y0211*
X01766Y02114*
X01769Y02119*
X01771Y02126*
X01769Y02132*
X01766Y02137*
X01761Y02141*
X01754Y02142*
G37*
G36*
X01619Y02137D02*
X01613Y02136D01*
X01608Y02132*
X01604Y02127*
X01603Y02121*
X01604Y02114*
X01608Y02109*
X01613Y02105*
X01619Y02104*
X01626Y02105*
X01631Y02109*
X01634Y02114*
X01636Y02121*
X01634Y02127*
X01631Y02132*
X01626Y02136*
X01619Y02137*
G37*
G36*
X01696Y02115D02*
X01689Y02114D01*
X01682Y02109*
X01678Y02103*
X01677Y02096*
X01678Y02088*
X01682Y02082*
X01689Y02078*
X01696Y02077*
X01703Y02078*
X0171Y02082*
X01714Y02088*
X01715Y02096*
X01714Y02103*
X0171Y02109*
X01703Y02114*
X01696Y02115*
G37*
G36*
X01884Y02087D02*
X01878Y02086D01*
X01873Y02082*
X01869Y02077*
X01868Y02071*
X01869Y02064*
X01873Y02059*
X01878Y02055*
X01884Y02054*
X01891Y02055*
X01896Y02059*
X01899Y02064*
X01901Y02071*
X01899Y02077*
X01896Y02082*
X01891Y02086*
X01884Y02087*
G37*
G36*
X01568Y02084D02*
X01561Y02082D01*
X01556Y02079*
X01553Y02073*
X01551Y02067*
X01553Y02061*
X01556Y02056*
X01561Y02052*
X01568Y02051*
X01574Y02052*
X01579Y02056*
X01583Y02061*
X01584Y02067*
X01583Y02073*
X01579Y02079*
X01574Y02082*
X01568Y02084*
G37*
G36*
X03571Y02115D02*
X03564Y02114D01*
X03557Y02109*
X03553Y02103*
X03552Y02096*
X03553Y02088*
X03557Y02082*
X03564Y02078*
X03565Y02078*
X03565Y02073*
X03565Y02073*
X0356Y02069*
X03556Y02064*
X03555Y02058*
X03556Y02051*
X03558Y02049*
X03559Y02045*
X03558Y02041*
X03556Y02039*
X03555Y02033*
X03556Y02026*
X0356Y02021*
X03565Y02017*
X03571Y02016*
X03578Y02017*
X03583Y02021*
X03586Y02026*
X03588Y02033*
X03586Y02039*
X03585Y02041*
X03583Y02045*
X03585Y02049*
X03586Y02051*
X03588Y02058*
X03586Y02064*
X03583Y02069*
X03578Y02073*
X03577Y02073*
Y02078*
X03578Y02078*
X03584Y02082*
X03589Y02088*
X0359Y02096*
X03589Y02103*
X03584Y02109*
X03578Y02114*
X03571Y02115*
G37*
G36*
X02409Y01983D02*
X02403Y01982D01*
X02398Y01978*
X02394Y01973*
X02393Y01967*
X02394Y0196*
X02396Y01958*
X02392Y01955*
X02391Y01956*
X02384Y01957*
X02378Y01956*
X02373Y01952*
X02369Y01947*
X02368Y01941*
X02369Y01934*
X02373Y01929*
X02378Y01925*
X02384Y01924*
X02391Y01925*
X02396Y01929*
X02399Y01934*
X02401Y01941*
X02399Y01947*
X02398Y01949*
X02402Y01952*
X02403Y01951*
X02409Y0195*
X02416Y01951*
X02421Y01955*
X02424Y0196*
X02426Y01967*
X02424Y01973*
X02421Y01978*
X02416Y01982*
X02409Y01983*
G37*
G36*
X03298Y01987D02*
X03292Y01986D01*
X03287Y01982*
X03283Y01977*
X03282Y01971*
X03283Y01964*
X03287Y01959*
X03292Y01955*
X03298Y01954*
X03305Y01955*
X0331Y01959*
X03313Y01964*
X03315Y01971*
X03313Y01977*
X0331Y01982*
X03305Y01986*
X03298Y01987*
G37*
G36*
X01009Y01972D02*
X01003Y01971D01*
X00998Y01967*
X00994Y01962*
X00993Y01956*
X00994Y01949*
X00998Y01944*
X01003Y0194*
X01009Y01939*
X01016Y0194*
X01021Y01944*
X01024Y01949*
X01026Y01956*
X01024Y01962*
X01021Y01967*
X01016Y01971*
X01009Y01972*
G37*
G36*
X02299Y01932D02*
X02293Y01931D01*
X02288Y01927*
X02284Y01922*
X02283Y01916*
X02284Y01909*
X02288Y01904*
X02293Y019*
X02299Y01899*
X02306Y019*
X02311Y01904*
X02314Y01909*
X02316Y01916*
X02314Y01922*
X02311Y01927*
X02306Y01931*
X02299Y01932*
G37*
G36*
X00199Y0202D02*
X00187Y02019D01*
X00175Y02015*
X00164Y02009*
X00154Y02001*
X00146Y01991*
X0014Y0198*
X00136Y01968*
X00135Y01956*
X00136Y01943*
X0014Y01931*
X00146Y0192*
X00154Y0191*
X00164Y01902*
X00175Y01896*
X00187Y01892*
X00199Y01891*
X00212Y01892*
X00224Y01896*
X00235Y01902*
X00245Y0191*
X00253Y0192*
X00259Y01931*
X00262Y01943*
X00264Y01956*
X00262Y01968*
X00259Y0198*
X00253Y01991*
X00245Y02001*
X00235Y02009*
X00224Y02015*
X00212Y02019*
X00199Y0202*
G37*
G36*
X03554Y01907D02*
X03548Y01906D01*
X03543Y01902*
X03539Y01897*
X03538Y01891*
X03539Y01884*
X03543Y01879*
X03548Y01875*
X03554Y01874*
X03561Y01875*
X03566Y01879*
X03569Y01884*
X03571Y01891*
X03569Y01897*
X03566Y01902*
X03561Y01906*
X03554Y01907*
G37*
G36*
X03392Y01887D02*
X03386Y01886D01*
X03381Y01882*
X03377Y01877*
X03376Y01871*
X03377Y01864*
X03381Y01859*
X03386Y01855*
X03392Y01854*
X03399Y01855*
X03404Y01859*
X03407Y01864*
X03409Y01871*
X03407Y01877*
X03404Y01882*
X03399Y01886*
X03392Y01887*
G37*
G36*
X03439Y01887D02*
X03433Y01886D01*
X03427Y01882*
X03424Y01877*
X03422Y0187*
X03424Y01864*
X03427Y01859*
X03433Y01855*
X03439Y01854*
X03445Y01855*
X0345Y01859*
X03454Y01864*
X03455Y0187*
X03454Y01877*
X0345Y01882*
X03445Y01886*
X03439Y01887*
G37*
G36*
X03804Y01856D02*
X03798Y01855D01*
X03793Y01851*
X03789Y01846*
X03788Y0184*
X03789Y01833*
X03793Y01828*
X03798Y01824*
X03804Y01823*
X03811Y01824*
X03816Y01828*
X03819Y01833*
X03821Y0184*
X03819Y01846*
X03816Y01851*
X03811Y01855*
X03804Y01856*
G37*
G36*
X03329Y01842D02*
X03322Y01841D01*
X03317Y01837*
X03314Y01832*
X03312Y01826*
X03314Y01819*
X03317Y01814*
X03322Y0181*
X03329Y01809*
X03335Y0181*
X0334Y01814*
X03344Y01819*
X03345Y01826*
X03344Y01832*
X0334Y01837*
X03335Y01841*
X03329Y01842*
G37*
G36*
X01393Y01833D02*
X01387Y01832D01*
X01382Y01828*
X01378Y01823*
X01377Y01816*
X01378Y0181*
X01382Y01805*
X01387Y01801*
X01393Y018*
X01399Y01801*
X01405Y01805*
X01408Y0181*
X0141Y01816*
X01408Y01823*
X01405Y01828*
X01399Y01832*
X01393Y01833*
G37*
G36*
X03944Y01832D02*
X03938Y01831D01*
X03933Y01827*
X03929Y01822*
X03928Y01816*
X03929Y01809*
X03933Y01804*
X03938Y018*
X03944Y01799*
X03951Y018*
X03956Y01804*
X03959Y01809*
X03961Y01816*
X03959Y01822*
X03956Y01827*
X03951Y01831*
X03944Y01832*
G37*
G36*
X03056Y01828D02*
X0305Y01826D01*
X03045Y01823*
X03041Y01818*
X0304Y01811*
X03041Y01805*
X03045Y018*
X0305Y01796*
X03056Y01795*
X03063Y01796*
X03068Y018*
X03071Y01805*
X03073Y01811*
X03071Y01818*
X03068Y01823*
X03063Y01826*
X03056Y01828*
G37*
G36*
X01879D02*
X01873Y01826D01*
X01868Y01823*
X01864Y01818*
X01863Y01811*
X01864Y01805*
X01868Y018*
X01873Y01796*
X01879Y01795*
X01886Y01796*
X01891Y018*
X01895Y01805*
X01896Y01811*
X01895Y01818*
X01891Y01823*
X01886Y01826*
X01879Y01828*
G37*
G36*
X04064Y01812D02*
X04058Y01811D01*
X04053Y01807*
X04049Y01802*
X04048Y01796*
X04049Y01789*
X04053Y01784*
X04058Y0178*
X04064Y01779*
X04071Y0178*
X04076Y01784*
X04079Y01789*
X04081Y01796*
X04079Y01802*
X04076Y01807*
X04071Y01811*
X04064Y01812*
G37*
G36*
X02579Y01806D02*
X02573Y01805D01*
X02568Y01801*
X02564Y01796*
X02563Y0179*
X02564Y01783*
X02568Y01778*
X02573Y01774*
X02579Y01773*
X02586Y01774*
X02591Y01778*
X02594Y01783*
X02596Y0179*
X02594Y01796*
X02591Y01801*
X02586Y01805*
X02579Y01806*
G37*
G36*
X02626Y01786D02*
X0262Y01785D01*
X02615Y01781*
X02611Y01776*
X0261Y0177*
X02611Y01763*
X02615Y01758*
X0262Y01754*
X02626Y01753*
X02633Y01754*
X02638Y01758*
X02641Y01763*
X02643Y0177*
X02641Y01776*
X02638Y01781*
X02633Y01785*
X02626Y01786*
G37*
G36*
X03719Y01782D02*
X03713Y01781D01*
X03708Y01777*
X03704Y01772*
X03703Y01766*
X03704Y01759*
X03708Y01754*
X03713Y0175*
X03719Y01749*
X03726Y0175*
X03731Y01754*
X03734Y01759*
X03736Y01766*
X03734Y01772*
X03731Y01777*
X03726Y01781*
X03719Y01782*
G37*
G36*
X02549Y01771D02*
X02543Y0177D01*
X02538Y01766*
X02534Y01761*
X02533Y01755*
X02534Y01748*
X02538Y01743*
X02543Y01739*
X02549Y01738*
X02556Y01739*
X02561Y01743*
X02564Y01748*
X02566Y01755*
X02564Y01761*
X02561Y01766*
X02556Y0177*
X02549Y01771*
G37*
G36*
X04134Y01767D02*
X04128Y01766D01*
X04123Y01762*
X04119Y01757*
X04118Y01751*
X04119Y01744*
X04123Y01739*
X04128Y01735*
X04134Y01734*
X04141Y01735*
X04146Y01739*
X04149Y01744*
X04151Y01751*
X04149Y01757*
X04146Y01762*
X04141Y01766*
X04134Y01767*
G37*
G36*
X02604Y0175D02*
X02598Y01749D01*
X02593Y01745*
X02589Y0174*
X02588Y01734*
X02589Y01727*
X02593Y01722*
X02598Y01718*
X02604Y01717*
X02611Y01718*
X02616Y01722*
X02619Y01727*
X02621Y01734*
X02619Y0174*
X02616Y01745*
X02611Y01749*
X02604Y0175*
G37*
G36*
X03197Y0173D02*
X03191Y01729D01*
X03185Y01725*
X03182Y0172*
X0318Y01714*
X03182Y01707*
X03185Y01702*
X03191Y01698*
X03197Y01697*
X03203Y01698*
X03208Y01702*
X03212Y01707*
X03213Y01714*
X03212Y0172*
X03208Y01725*
X03203Y01729*
X03197Y0173*
G37*
G36*
X03589Y01727D02*
X03583Y01726D01*
X03578Y01722*
X03574Y01717*
X03573Y01711*
X03574Y01704*
X03578Y01699*
X03583Y01695*
X03589Y01694*
X03596Y01695*
X03601Y01699*
X03604Y01704*
X03606Y01711*
X03604Y01717*
X03601Y01722*
X03596Y01726*
X03589Y01727*
G37*
G36*
X01015Y01722D02*
X01009Y0172D01*
X01004Y01717*
X01Y01711*
X00999Y01705*
X01Y01699*
X01004Y01694*
X01009Y0169*
X01015Y01689*
X01021Y0169*
X01027Y01694*
X0103Y01699*
X01032Y01705*
X0103Y01711*
X01027Y01717*
X01021Y0172*
X01015Y01722*
G37*
G36*
X03747Y01696D02*
X03741Y01695D01*
X03736Y01691*
X03732Y01686*
X03731Y01682*
X03726Y01681*
X03724Y01684*
X03718Y01688*
X03712Y01689*
X03706Y01688*
X03701Y01684*
X03697Y01679*
X03696Y01673*
X03697Y01666*
X03701Y01661*
X03706Y01658*
X03712Y01656*
X03718Y01658*
X03724Y01661*
X03727Y01666*
X03728Y0167*
X03733Y01671*
X03736Y01668*
X03741Y01664*
X03747Y01663*
X03753Y01664*
X03758Y01661*
X03758Y01659*
X03762Y01654*
X03767Y01651*
X03773Y01649*
X0378Y01651*
X03785Y01654*
X03788Y01659*
X0379Y01666*
X03788Y01672*
X03785Y01677*
X0378Y01681*
X03773Y01682*
X03767Y01681*
X03763Y01684*
X03762Y01686*
X03759Y01691*
X03753Y01695*
X03747Y01696*
G37*
G36*
X03803Y01707D02*
X03797Y01706D01*
X03792Y01702*
X03788Y01697*
X03787Y01691*
X03788Y01684*
X03792Y01679*
X03797Y01675*
X03803Y01674*
X0381Y01675*
X03815Y01679*
X03818Y01684*
X0382Y01691*
X03818Y01697*
X03815Y01702*
X0381Y01706*
X03803Y01707*
G37*
G36*
X01893Y01702D02*
X01887Y017D01*
X01882Y01697*
X01878Y01691*
X01877Y01685*
X01878Y01679*
X01882Y01674*
X01887Y0167*
X01893Y01669*
X019Y0167*
X01905Y01674*
X01908Y01679*
X0191Y01685*
X01908Y01691*
X01905Y01697*
X019Y017*
X01893Y01702*
G37*
G36*
X01822Y0169D02*
X01816Y01689D01*
X01811Y01685*
X01807Y0168*
X01806Y01674*
X01807Y01667*
X01811Y01662*
X01816Y01658*
X01822Y01657*
X01829Y01658*
X01834Y01662*
X01837Y01667*
X01839Y01674*
X01837Y0168*
X01834Y01685*
X01829Y01689*
X01822Y0169*
G37*
G36*
X03224Y01677D02*
X03218Y01676D01*
X03213Y01672*
X03209Y01667*
X03208Y01661*
X03209Y01655*
X03213Y01649*
X03218Y01646*
X03224Y01645*
X03231Y01646*
X03235Y01649*
X03239Y01649*
X03241Y01649*
X03246Y01645*
X03252Y01644*
X03259Y01645*
X03264Y01649*
X03267Y01654*
X03269Y01661*
X03267Y01667*
X03264Y01672*
X03259Y01676*
X03252Y01677*
X03246Y01676*
X03242Y01673*
X03238Y01672*
X03235Y01673*
X03231Y01676*
X03224Y01677*
G37*
G36*
X02666Y01656D02*
X0266Y01655D01*
X02655Y01651*
X02651Y01646*
X0265Y0164*
X02651Y01635*
X02647Y01631*
X02647Y01631*
X02643Y01632*
X02637Y01631*
X02632Y01627*
X02628Y01622*
X02627Y01616*
X02628Y01609*
X02632Y01604*
X02637Y016*
X02643Y01599*
X0265Y016*
X02655Y01604*
X02658Y01609*
X0266Y01616*
X02659Y0162*
X02662Y01624*
X02663Y01624*
X02666Y01623*
X02673Y01624*
X02678Y01628*
X02681Y01633*
X02683Y0164*
X02681Y01646*
X02678Y01651*
X02673Y01655*
X02666Y01656*
G37*
G36*
X06838Y01674D02*
X06829Y01672D01*
X06821Y01666*
X06815Y01658*
X06814Y01649*
X06815Y0164*
X06821Y01632*
X06829Y01627*
X06838Y01625*
X06847Y01627*
X06855Y01632*
X06861Y0164*
X06863Y01649*
X06861Y01658*
X06855Y01666*
X06847Y01672*
X06838Y01674*
G37*
G36*
X04134Y01667D02*
X04128Y01666D01*
X04123Y01662*
X04119Y01657*
X04118Y01651*
X04119Y01644*
X04123Y01639*
X04128Y01635*
X04133Y01634*
X04135Y01631*
X04136Y01629*
X04136Y01629*
X04134Y01623*
X04136Y01617*
X04139Y01612*
X04145Y01608*
X04151Y01607*
X04157Y01608*
X04161Y01611*
X04164Y01607*
X04164Y01607*
X04163Y01601*
X04164Y01594*
X04168Y01589*
X04173Y01585*
X04179Y01584*
X04186Y01585*
X04191Y01589*
X04194Y01594*
X04196Y01601*
X04194Y01607*
X04191Y01612*
X04186Y01616*
X04179Y01617*
X04173Y01616*
X04169Y01613*
X04166Y01617*
X04166Y01617*
X04167Y01623*
X04166Y01629*
X04162Y01635*
X04157Y01638*
X04152Y01639*
X0415Y01643*
X04149Y01644*
X04149Y01644*
X04151Y01651*
X04149Y01657*
X04146Y01662*
X04141Y01666*
X04134Y01667*
G37*
G36*
X02719Y01607D02*
X02713Y01606D01*
X02708Y01602*
X02704Y01597*
X02703Y01591*
X02704Y01584*
X02708Y01579*
X02713Y01575*
X02719Y01574*
X02726Y01575*
X02731Y01579*
X02734Y01584*
X02736Y01591*
X02734Y01597*
X02731Y01602*
X02726Y01606*
X02719Y01607*
G37*
G36*
X03894Y01582D02*
X03888Y01581D01*
X03883Y01577*
X03879Y01572*
X03878Y01566*
X03879Y01559*
X03883Y01554*
X03888Y0155*
X03894Y01549*
X03901Y0155*
X03906Y01554*
X03909Y01559*
X03911Y01566*
X03909Y01572*
X03906Y01577*
X03901Y01581*
X03894Y01582*
G37*
G36*
X03969Y01568D02*
X03963Y01567D01*
X03958Y01563*
X03954Y01558*
X03953Y01552*
X03954Y01545*
X03958Y0154*
X03963Y01536*
X03969Y01535*
X03976Y01536*
X03978Y01538*
X03983Y01539*
X03985Y01537*
X03988Y01535*
X03994Y01534*
X04001Y01535*
X04006Y01539*
X04009Y01544*
X04011Y01551*
X04009Y01557*
X04006Y01562*
X04001Y01566*
X03994Y01567*
X03988Y01566*
X03986Y01564*
X03981Y01563*
X03979Y01565*
X03976Y01567*
X03969Y01568*
G37*
G36*
X04034Y01562D02*
X04028Y01561D01*
X04023Y01557*
X04019Y01552*
X04018Y01546*
X04019Y01539*
X04023Y01534*
X04028Y0153*
X04034Y01529*
X04041Y0153*
X04046Y01534*
X04049Y01539*
X04051Y01546*
X04049Y01552*
X04046Y01557*
X04041Y01561*
X04034Y01562*
G37*
G36*
X03924Y01552D02*
X03918Y01551D01*
X03913Y01547*
X03909Y01542*
X03908Y01536*
X03909Y01529*
X03913Y01524*
X03918Y0152*
X03924Y01519*
X03931Y0152*
X03936Y01524*
X03939Y01529*
X03941Y01536*
X03939Y01542*
X03936Y01547*
X03931Y01551*
X03924Y01552*
G37*
G36*
X02894Y01577D02*
X02888Y01576D01*
X02883Y01572*
X02879Y01567*
X02878Y01561*
X02879Y01554*
X02883Y01549*
X02888Y01545*
X02894Y01544*
X02901Y01545*
X02901Y01546*
X02904Y01542*
X02904Y01542*
X02903Y01536*
X02904Y01529*
X02908Y01524*
X02913Y0152*
X02919Y01519*
X02926Y0152*
X02931Y01524*
X02934Y01529*
X02936Y01536*
X02934Y01542*
X02931Y01547*
X02926Y01551*
X02919Y01552*
X02913Y01551*
X02913Y0155*
X02909Y01554*
X02909Y01554*
X02911Y01561*
X02909Y01567*
X02906Y01572*
X02901Y01576*
X02894Y01577*
G37*
G36*
X01719Y01552D02*
X01713Y01551D01*
X01708Y01547*
X01704Y01542*
X01703Y01536*
X01704Y01529*
X01708Y01524*
X01713Y0152*
X01719Y01519*
X01726Y0152*
X01731Y01524*
X01734Y01529*
X01736Y01536*
X01734Y01542*
X01731Y01547*
X01726Y01551*
X01719Y01552*
G37*
G36*
X01897Y01532D02*
X01891Y01531D01*
X01885Y01528*
X01882Y01522*
X0188Y01516*
X01882Y0151*
X01885Y01504*
X01891Y01501*
X01897Y015*
X01903Y01501*
X01908Y01504*
X01912Y0151*
X01913Y01516*
X01912Y01522*
X01908Y01528*
X01903Y01531*
X01897Y01532*
G37*
G36*
X04064Y01527D02*
X04058Y01526D01*
X04053Y01522*
X04049Y01517*
X04048Y01511*
X04049Y01504*
X04053Y01499*
X04058Y01495*
X04064Y01494*
X04071Y01495*
X04076Y01499*
X04079Y01504*
X04081Y01511*
X04079Y01517*
X04076Y01522*
X04071Y01526*
X04064Y01527*
G37*
G36*
X03864D02*
X03858Y01526D01*
X03853Y01522*
X03849Y01517*
X03848Y01511*
X03849Y01504*
X03853Y01499*
X03858Y01495*
X03864Y01494*
X03871Y01495*
X03876Y01499*
X03879Y01504*
X03881Y01511*
X03879Y01517*
X03876Y01522*
X03871Y01526*
X03864Y01527*
G37*
G36*
X02274Y01522D02*
X02268Y01521D01*
X02263Y01517*
X02259Y01512*
X02258Y01506*
X02259Y01499*
X02263Y01494*
X02268Y0149*
X02274Y01489*
X02281Y0149*
X02286Y01494*
X02289Y01499*
X02291Y01506*
X02289Y01512*
X02286Y01517*
X02281Y01521*
X02274Y01522*
G37*
G36*
X03834Y01497D02*
X03828Y01496D01*
X03823Y01492*
X03819Y01487*
X03818Y01481*
X03819Y01474*
X03823Y01469*
X03828Y01465*
X03834Y01464*
X03841Y01465*
X03846Y01469*
X03849Y01474*
X03851Y01481*
X03849Y01487*
X03846Y01492*
X03841Y01496*
X03834Y01497*
G37*
G36*
X02694D02*
X02688Y01496D01*
X02683Y01492*
X02679Y01487*
X02678Y01481*
X02679Y01474*
X02683Y01469*
X02688Y01465*
X02694Y01464*
X02701Y01465*
X02706Y01469*
X02709Y01474*
X02711Y01481*
X02709Y01487*
X02706Y01492*
X02701Y01496*
X02694Y01497*
G37*
G36*
X03549Y01457D02*
X03543Y01456D01*
X03538Y01452*
X03534Y01447*
X03533Y01441*
X03534Y01434*
X03538Y01429*
X03543Y01425*
X03549Y01424*
X03556Y01425*
X03561Y01429*
X03564Y01434*
X03566Y01441*
X03564Y01447*
X03561Y01452*
X03556Y01456*
X03549Y01457*
G37*
G36*
X02446Y01453D02*
X0244Y01452D01*
X02435Y01448*
X02431Y01443*
X0243Y01437*
X02431Y0143*
X02435Y01425*
X0244Y01421*
X02446Y0142*
X02453Y01421*
X02458Y01425*
X02461Y0143*
X02463Y01437*
X02461Y01443*
X02458Y01448*
X02453Y01452*
X02446Y01453*
G37*
G36*
X01008Y01446D02*
X01002Y01445D01*
X00997Y01441*
X00993Y01436*
X00992Y0143*
X00993Y01423*
X00997Y01418*
X01002Y01414*
X01008Y01413*
X01015Y01414*
X0102Y01418*
X01023Y01423*
X01025Y0143*
X01023Y01436*
X0102Y01441*
X01015Y01445*
X01008Y01446*
G37*
G36*
X02083Y01427D02*
X02077Y01426D01*
X02072Y01423*
X02068Y01417*
X02067Y01411*
X02068Y01405*
X02068Y01405*
X02066Y01402*
X02065Y01401*
X02059Y01402*
X02053Y01401*
X02048Y01397*
X02044Y01392*
X02043Y01386*
X02044Y01379*
X02048Y01374*
X02053Y0137*
X02059Y01369*
X02066Y0137*
X02071Y01374*
X02074Y01379*
X02076Y01386*
X02074Y01392*
X02074Y01392*
X02076Y01395*
X02078Y01396*
X02083Y01395*
X0209Y01396*
X02095Y014*
X02098Y01405*
X021Y01411*
X02098Y01417*
X02095Y01423*
X0209Y01426*
X02083Y01427*
G37*
G36*
X03407Y01427D02*
X03401Y01426D01*
X03395Y01422*
X03392Y01417*
X0339Y01411*
X03392Y01405*
X03395Y014*
X03391Y01397*
X03386Y01401*
X03379Y01402*
X03373Y01401*
X03368Y01397*
X03364Y01392*
X03363Y01386*
X03364Y01379*
X03368Y01374*
X03373Y0137*
X03379Y01369*
X03385Y0137*
X03388Y01368*
X03389Y01367*
X03388Y01363*
X03389Y01357*
X03392Y01353*
X03392Y01352*
X03389Y01349*
X03388Y01349*
X03386Y01351*
X03379Y01352*
X03373Y01351*
X03368Y01347*
X03364Y01342*
X03363Y01336*
X03364Y01329*
X03368Y01324*
X03373Y0132*
X03379Y01319*
X03386Y0132*
X03391Y01324*
X03394Y01329*
X03396Y01336*
X03394Y01342*
X03392Y01345*
X03392Y01346*
X03395Y0135*
X03396Y01349*
X03398Y01348*
X03404Y01347*
X03411Y01348*
X03416Y01351*
X03419Y01357*
X03421Y01363*
X03419Y01369*
X03416Y01374*
X03411Y01378*
X03404Y01379*
X03399Y01378*
X03396Y0138*
X03395Y01382*
X03396Y01386*
X03394Y01392*
X03391Y01396*
X03395Y01399*
X03401Y01396*
X03407Y01395*
X03413Y01396*
X03418Y01399*
X03422Y01405*
X03423Y01411*
X03422Y01417*
X03418Y01422*
X03413Y01426*
X03407Y01427*
G37*
G36*
X00199Y01495D02*
X00187Y01494D01*
X00175Y0149*
X00164Y01484*
X00154Y01476*
X00146Y01466*
X0014Y01455*
X00136Y01443*
X00135Y01431*
X00136Y01418*
X0014Y01406*
X00146Y01395*
X00154Y01385*
X00164Y01377*
X00175Y01371*
X00187Y01367*
X00199Y01366*
X00212Y01367*
X00224Y01371*
X00235Y01377*
X00245Y01385*
X00253Y01395*
X00259Y01406*
X00262Y01418*
X00264Y01431*
X00262Y01443*
X00259Y01455*
X00253Y01466*
X00245Y01476*
X00235Y01484*
X00224Y0149*
X00212Y01494*
X00199Y01495*
G37*
G36*
X02028Y01377D02*
X02022Y01376D01*
X02017Y01373*
X02013Y01367*
X02012Y01361*
X02013Y01355*
X02013Y01355*
X02011Y01352*
X0201Y01351*
X02004Y01352*
X01998Y01351*
X01993Y01347*
X01989Y01342*
X01988Y01336*
X01989Y01329*
X01993Y01324*
X01998Y0132*
X02004Y01319*
X02011Y0132*
X02016Y01324*
X02019Y01329*
X02021Y01336*
X02019Y01342*
X02019Y01342*
X02021Y01345*
X02023Y01346*
X02028Y01345*
X02035Y01346*
X0204Y0135*
X02043Y01355*
X02045Y01361*
X02043Y01367*
X0204Y01373*
X02035Y01376*
X02028Y01377*
G37*
G36*
X02502Y01332D02*
X02496Y01331D01*
X02491Y01327*
X02487Y01322*
X02486Y01316*
X02487Y01309*
X02491Y01304*
X02496Y013*
X02502Y01299*
X02509Y013*
X02514Y01304*
X02517Y01309*
X02519Y01316*
X02517Y01322*
X02514Y01327*
X02509Y01331*
X02502Y01332*
G37*
G36*
X01696Y01328D02*
X01689Y01326D01*
X01682Y01322*
X01678Y01316*
X01677Y01308*
X01678Y01301*
X01682Y01295*
X01689Y01291*
X01696Y01289*
X01703Y01291*
X0171Y01295*
X01714Y01301*
X01715Y01308*
X01714Y01316*
X0171Y01322*
X01703Y01326*
X01696Y01328*
G37*
G36*
X03571Y01328D02*
X03564Y01326D01*
X03557Y01322*
X03553Y01316*
X03552Y01308*
X03553Y01301*
X03557Y01295*
X03564Y01291*
X03571Y01289*
X03578Y01291*
X03584Y01295*
X03589Y01301*
X0359Y01308*
X03589Y01316*
X03584Y01322*
X03578Y01326*
X03571Y01328*
G37*
G36*
X01798Y0132D02*
X01791Y01319D01*
X01786Y01315*
X01783Y0131*
X01781Y01304*
X01783Y01297*
X01786Y01292*
X01791Y01289*
X01798Y01287*
X01804Y01289*
X01809Y01292*
X01813Y01297*
X01814Y01304*
X01813Y0131*
X01809Y01315*
X01804Y01319*
X01798Y0132*
G37*
G36*
X02206Y01314D02*
X022Y01313D01*
X02195Y01309*
X02191Y01304*
X0219Y01298*
X02191Y01291*
X02195Y01286*
X022Y01282*
X02206Y01281*
X02213Y01282*
X02218Y01286*
X02221Y01291*
X02223Y01298*
X02221Y01304*
X02218Y01309*
X02213Y01313*
X02206Y01314*
G37*
G36*
X01567Y01301D02*
X01561Y013D01*
X01556Y01296*
X01552Y01291*
X01551Y01285*
X01552Y01279*
X01556Y01273*
X01561Y0127*
X01567Y01269*
X01574Y0127*
X01579Y01273*
X01582Y01279*
X01584Y01285*
X01582Y01291*
X01579Y01296*
X01574Y013*
X01567Y01301*
G37*
G36*
X01003Y01193D02*
X00997Y01192D01*
X00992Y01188*
X00988Y01183*
X00987Y01177*
X00988Y0117*
X00992Y01165*
X00997Y01162*
X01003Y0116*
X0101Y01162*
X01015Y01165*
X01019Y0117*
X0102Y01177*
X01019Y01183*
X01015Y01188*
X0101Y01192*
X01003Y01193*
G37*
G36*
X02826Y00992D02*
X0282Y00991D01*
X02815Y00987*
X0281*
X02805Y00991*
X02799Y00992*
X02792Y00991*
X02787Y00987*
X02786Y00986*
X0278*
X02779Y00987*
X02773Y00991*
X02767Y00992*
X02761Y00991*
X02756Y00987*
X02751*
X02746Y00991*
X0274Y00992*
X02733Y00991*
X02728Y00987*
X02727Y00986*
X02721*
X0272Y00987*
X02714Y00991*
X02708Y00992*
X02702Y00991*
X02697Y00987*
X02692*
X02687Y00991*
X02681Y00992*
X02674Y00991*
X02669Y00987*
X02668Y00986*
X02662*
X02661Y00987*
X02655Y00991*
X02649Y00992*
X02643Y00991*
X02638Y00987*
X02633*
X02628Y00991*
X02622Y00992*
X02615Y00991*
X0261Y00987*
X02606Y00982*
X02605Y00976*
X02606Y0097*
X0261Y00964*
X02615Y00961*
X02622Y0096*
X02628Y00961*
X02633Y00964*
X02638*
X02643Y00961*
X02649Y0096*
X02655Y00961*
X02661Y00964*
X02662Y00966*
X02668*
X02669Y00964*
X02674Y00961*
X02681Y0096*
X02687Y00961*
X02692Y00964*
X02697*
X02702Y00961*
X02708Y0096*
X02714Y00961*
X0272Y00964*
X02721Y00966*
X02727*
X02728Y00964*
X02733Y00961*
X0274Y0096*
X02746Y00961*
X02751Y00964*
X02756*
X02761Y00961*
X02767Y0096*
X02773Y00961*
X02779Y00964*
X0278Y00966*
X02786*
X02787Y00964*
X02792Y00961*
X02799Y0096*
X02805Y00961*
X0281Y00964*
X02815*
X0282Y00961*
X02826Y0096*
X02833Y00961*
X02838Y00964*
X02841Y0097*
X02843Y00976*
X02841Y00982*
X02838Y00987*
X02833Y00991*
X02826Y00992*
G37*
G36*
X04366Y01045D02*
X04289D01*
Y00968*
X04366*
Y01045*
G37*
G36*
X05327Y01046D02*
X05317Y01045D01*
X05308Y01041*
X053Y01034*
X05294Y01026*
X0529Y01017*
X05288Y01007*
X0529Y00997*
X05294Y00988*
X053Y0098*
X05308Y00973*
X05317Y00969*
X05327Y00968*
X05337Y00969*
X05347Y00973*
X05355Y0098*
X05361Y00988*
X05365Y00997*
X05366Y01007*
X05365Y01017*
X05361Y01026*
X05355Y01034*
X05347Y01041*
X05337Y01045*
X05327Y01046*
G37*
G36*
X05127D02*
X05117Y01045D01*
X05108Y01041*
X051Y01034*
X05094Y01026*
X0509Y01017*
X05088Y01007*
X0509Y00997*
X05094Y00988*
X051Y0098*
X05108Y00973*
X05117Y00969*
X05127Y00968*
X05137Y00969*
X05147Y00973*
X05155Y0098*
X05161Y00988*
X05165Y00997*
X05166Y01007*
X05165Y01017*
X05161Y01026*
X05155Y01034*
X05147Y01041*
X05137Y01045*
X05127Y01046*
G37*
G36*
X04927D02*
X04917Y01045D01*
X04908Y01041*
X049Y01034*
X04894Y01026*
X0489Y01017*
X04888Y01007*
X0489Y00997*
X04894Y00988*
X049Y0098*
X04908Y00973*
X04917Y00969*
X04927Y00968*
X04937Y00969*
X04947Y00973*
X04955Y0098*
X04961Y00988*
X04965Y00997*
X04966Y01007*
X04965Y01017*
X04961Y01026*
X04955Y01034*
X04947Y01041*
X04937Y01045*
X04927Y01046*
G37*
G36*
X0299Y00976D02*
X02982Y00975D01*
X02976Y00971*
X02972Y00965*
X0297Y00957*
X02972Y0095*
X02976Y00944*
X02982Y00939*
X0299Y00938*
X02997Y00939*
X03003Y00944*
X03007Y0095*
X03009Y00957*
X03007Y00965*
X03003Y00971*
X02997Y00975*
X0299Y00976*
G37*
G36*
X02202D02*
X02195Y00975D01*
X02189Y00971*
X02185Y00965*
X02183Y00957*
X02185Y0095*
X02189Y00944*
X02195Y00939*
X02202Y00938*
X0221Y00939*
X02216Y00944*
X0222Y0095*
X02221Y00957*
X0222Y00965*
X02216Y00971*
X0221Y00975*
X02202Y00976*
G37*
G36*
X02478Y00953D02*
X02472Y00952D01*
X02467Y00948*
X02463Y00943*
X02462Y00937*
X02463Y0093*
X02467Y00925*
X02472Y00921*
X02478Y0092*
X02485Y00921*
X0249Y00925*
X02493Y0093*
X02495Y00937*
X02493Y00943*
X0249Y00948*
X02485Y00952*
X02478Y00953*
G37*
G36*
X01004Y00922D02*
X00998Y00921D01*
X00993Y00917*
X00989Y00912*
X00988Y00906*
X00989Y00899*
X00993Y00894*
X00998Y0089*
X01004Y00889*
X01011Y0089*
X01016Y00894*
X01019Y00899*
X01021Y00906*
X01019Y00912*
X01016Y00917*
X01011Y00921*
X01004Y00922*
G37*
G36*
X03617Y00982D02*
X03604Y00981D01*
X03591Y00977*
X0358Y00971*
X03569Y00963*
X03561Y00952*
X03555Y00941*
X03551Y00928*
X0355Y00915*
X03551Y00902*
X03555Y00889*
X03561Y00877*
X03569Y00867*
X0358Y00859*
X03591Y00853*
X03604Y00849*
X03617Y00847*
X0363Y00849*
X03643Y00853*
X03654Y00859*
X03665Y00867*
X03673Y00877*
X03679Y00889*
X03683Y00902*
X03684Y00915*
X03683Y00928*
X03679Y00941*
X03673Y00952*
X03665Y00963*
X03654Y00971*
X03643Y00977*
X0363Y00981*
X03617Y00982*
G37*
G36*
X01652D02*
X01639Y00981D01*
X01626Y00977*
X01615Y00971*
X01604Y00963*
X01596Y00952*
X0159Y00941*
X01586Y00928*
X01585Y00915*
X01586Y00902*
X0159Y00889*
X01596Y00877*
X01604Y00867*
X01615Y00859*
X01626Y00853*
X01639Y00849*
X01652Y00847*
X01665Y00849*
X01678Y00853*
X01689Y00859*
X017Y00867*
X01708Y00877*
X01714Y00889*
X01718Y00902*
X01719Y00915*
X01718Y00928*
X01714Y00941*
X01708Y00952*
X017Y00963*
X01689Y00971*
X01678Y00977*
X01665Y00981*
X01652Y00982*
G37*
G36*
X05578Y00936D02*
X05566Y00934D01*
X05555Y0093*
X05545Y00923*
X05538Y00913*
X05533Y00902*
X05532Y0089*
X05533Y00878*
X05538Y00867*
X05545Y00858*
X05555Y0085*
X05566Y00846*
X05578Y00844*
X0559Y00846*
X05601Y0085*
X0561Y00858*
X05617Y00867*
X05622Y00878*
X05624Y0089*
X05622Y00902*
X05617Y00913*
X0561Y00923*
X05601Y0093*
X0559Y00934*
X05578Y00936*
G37*
G36*
X03979D02*
X03967Y00934D01*
X03956Y0093*
X03947Y00923*
X03939Y00913*
X03935Y00902*
X03933Y0089*
X03935Y00878*
X03939Y00867*
X03947Y00858*
X03956Y0085*
X03967Y00846*
X03979Y00844*
X03991Y00846*
X04002Y0085*
X04012Y00858*
X04019Y00867*
X04024Y00878*
X04025Y0089*
X04024Y00902*
X04019Y00913*
X04012Y00923*
X04002Y0093*
X03991Y00934*
X03979Y00936*
G37*
G36*
X00199Y0097D02*
X00187Y00969D01*
X00175Y00965*
X00164Y00959*
X00154Y00951*
X00146Y00941*
X0014Y0093*
X00136Y00918*
X00135Y00906*
X00136Y00893*
X0014Y00881*
X00146Y0087*
X00154Y0086*
X00164Y00852*
X00175Y00846*
X00187Y00842*
X00199Y00841*
X00212Y00842*
X00224Y00846*
X00235Y00852*
X00245Y0086*
X00253Y0087*
X00259Y00881*
X00262Y00893*
X00264Y00906*
X00262Y00918*
X00259Y0093*
X00253Y00941*
X00245Y00951*
X00235Y00959*
X00224Y00965*
X00212Y00969*
X00199Y0097*
G37*
G36*
X02759Y00811D02*
X02753Y0081D01*
X02748Y00806*
X02743*
X02738Y0081*
X02732Y00811*
X02726Y0081*
X0272Y00806*
X02717Y00801*
X02715Y00795*
X02717Y00789*
X0272Y00783*
X02726Y0078*
X02732Y00778*
X02738Y0078*
X02743Y00783*
X02748*
X02753Y0078*
X02759Y00778*
X02766Y0078*
X02771Y00783*
X02774Y00789*
X02776Y00795*
X02774Y00801*
X02771Y00806*
X02766Y0081*
X02759Y00811*
G37*
G36*
X02692D02*
X02686Y0081D01*
X02681Y00806*
X02676*
X02671Y0081*
X02665Y00811*
X02659Y0081*
X02653Y00806*
X0265Y00801*
X02649Y00795*
X0265Y00789*
X02653Y00783*
X02659Y0078*
X02665Y00778*
X02671Y0078*
X02676Y00783*
X02681*
X02686Y0078*
X02692Y00778*
X02699Y0078*
X02704Y00783*
X02707Y00789*
X02709Y00795*
X02707Y00801*
X02704Y00806*
X02699Y0081*
X02692Y00811*
G37*
G36*
X02625D02*
X02619Y0081D01*
X02614Y00806*
X02609*
X02604Y0081*
X02598Y00811*
X02592Y0081*
X02586Y00806*
X02583Y00801*
X02582Y00795*
X02583Y00789*
X02586Y00783*
X02592Y0078*
X02598Y00778*
X02604Y0078*
X02609Y00783*
X02614*
X02619Y0078*
X02625Y00778*
X02632Y0078*
X02637Y00783*
X02641Y00789*
X02642Y00795*
X02641Y00801*
X02637Y00806*
X02632Y0081*
X02625Y00811*
G37*
G36*
X02893D02*
X02887Y0081D01*
X02882Y00806*
X0288Y00805*
X02874*
X02873Y00806*
X02868Y0081*
X02862Y00811*
X02855Y0081*
X0285Y00806*
X02847Y00801*
X02847Y00801*
X02841*
X02841Y00801*
X02838Y00806*
X02833Y0081*
X02826Y00811*
X0282Y0081*
X02815Y00806*
X0281*
X02805Y0081*
X02799Y00811*
X02792Y0081*
X02787Y00806*
X02784Y00801*
X02782Y00795*
X02784Y00789*
X02787Y00783*
X02792Y0078*
X02799Y00778*
X02805Y0078*
X0281Y00783*
X02815*
X0282Y0078*
X02826Y00778*
X02833Y0078*
X02838Y00783*
X02841Y00789*
X02841Y00789*
X02847*
X02847Y00789*
X0285Y00783*
X02855Y0078*
X02862Y00778*
X02868Y0078*
X02873Y00783*
X02874Y00785*
X0288*
X02882Y00783*
X02887Y0078*
X02893Y00778*
X02899Y0078*
X02905Y00783*
X02908Y00789*
X0291Y00795*
X02908Y00801*
X02905Y00806*
X02899Y0081*
X02893Y00811*
G37*
G36*
X0099Y00703D02*
X00983Y00702D01*
X00978Y00698*
X00975Y00693*
X00973Y00687*
X00975Y0068*
X00978Y00675*
X00983Y00671*
X0099Y0067*
X00996Y00671*
X01001Y00675*
X01005Y0068*
X01006Y00687*
X01005Y00693*
X01001Y00698*
X00996Y00702*
X0099Y00703*
G37*
G36*
X02469Y00427D02*
X02463Y00426D01*
X02458Y00422*
X02454Y00417*
X02453Y0041*
X02454Y00404*
X02458Y00399*
X02463Y00395*
X02469Y00394*
X02476Y00395*
X02481Y00399*
X02484Y00404*
X02486Y0041*
X02484Y00417*
X02481Y00422*
X02476Y00426*
X02469Y00427*
G37*
G36*
X0298Y00425D02*
X02974Y00424D01*
X02968Y0042*
X02965Y00415*
X02964Y00409*
X02965Y00402*
X02968Y00397*
X02974Y00394*
X0298Y00392*
X02986Y00394*
X02991Y00397*
X02995Y00402*
X02996Y00409*
X02995Y00415*
X02991Y0042*
X02986Y00424*
X0298Y00425*
G37*
G36*
X03019Y00421D02*
X03013Y0042D01*
X03008Y00417*
X03004Y00411*
X03003Y00405*
X03004Y00399*
X03008Y00393*
X03013Y0039*
X03019Y00389*
X03025Y0039*
X03031Y00393*
X03034Y00399*
X03036Y00405*
X03034Y00411*
X03031Y00417*
X03025Y0042*
X03019Y00421*
G37*
G36*
X02821Y00424D02*
X02815Y00422D01*
X0281Y00419*
X02806Y00414*
X02805Y00407*
X02806Y00401*
X0281Y00396*
X02815Y00392*
X02821Y00391*
X02828Y00392*
X02833Y00396*
X02834Y00397*
X02835Y00398*
X0284Y00397*
X02842Y00393*
X02848Y0039*
X02854Y00389*
X0286Y0039*
X02865Y00393*
X02869Y00399*
X0287Y00405*
X02869Y00411*
X02865Y00417*
X0286Y0042*
X02854Y00421*
X02848Y0042*
X02842Y00417*
X02841Y00415*
X02841Y00415*
X02835Y00415*
X02833Y00419*
X02828Y00422*
X02821Y00424*
G37*
G36*
X02704Y00421D02*
X02698Y0042D01*
X02693Y00417*
X02689Y00411*
X02688Y00405*
X02689Y00399*
X02693Y00393*
X02698Y0039*
X02704Y00389*
X0271Y0039*
X02716Y00393*
X02719Y00399*
X02721Y00405*
X02719Y00411*
X02716Y00417*
X0271Y0042*
X02704Y00421*
G37*
G36*
X02665D02*
X02659Y0042D01*
X02653Y00417*
X0265Y00411*
X02649Y00405*
X0265Y00399*
X02653Y00393*
X02659Y0039*
X02665Y00389*
X02671Y0039*
X02676Y00393*
X0268Y00399*
X02681Y00405*
X0268Y00411*
X02676Y00417*
X02671Y0042*
X02665Y00421*
G37*
G36*
X02511D02*
X02505Y0042D01*
X025Y00417*
X02496Y00411*
X02495Y00405*
X02496Y00399*
X025Y00393*
X02505Y0039*
X02511Y00389*
X02518Y0039*
X02523Y00393*
X02526Y00399*
X02528Y00405*
X02526Y00411*
X02523Y00417*
X02518Y0042*
X02511Y00421*
G37*
G36*
X02389D02*
X02383Y0042D01*
X02378Y00417*
X02374Y00411*
X02373Y00405*
X02374Y00399*
X02378Y00393*
X02383Y0039*
X02389Y00389*
X02396Y0039*
X02401Y00393*
X02404Y00399*
X02406Y00405*
X02404Y00411*
X02401Y00417*
X02396Y0042*
X02389Y00421*
G37*
G36*
X0235D02*
X02344Y0042D01*
X02338Y00417*
X02335Y00411*
X02334Y00405*
X02335Y00399*
X02338Y00393*
X02344Y0039*
X0235Y00389*
X02356Y0039*
X02361Y00393*
X02365Y00399*
X02366Y00405*
X02365Y00411*
X02361Y00417*
X02356Y0042*
X0235Y00421*
G37*
G36*
X01872Y00303D02*
X01865Y00302D01*
X01862Y003*
X01858Y00302*
X01852Y00303*
X01846Y00302*
X01842Y003*
X01838Y00302*
X01832Y00303*
X01826Y00302*
X01821Y00298*
X01817Y00293*
X01816Y00287*
X01817Y00281*
X01821Y00275*
X01822Y00274*
Y00268*
X01821Y00267*
X01817Y00262*
X01816Y00255*
X01817Y00249*
X01821Y00244*
X01826Y0024*
X01832Y00239*
X01838Y0024*
X01842Y00243*
X01846Y0024*
X01852Y00239*
X01858Y0024*
X01862Y00243*
X01865Y0024*
X01872Y00239*
X01878Y0024*
X01883Y00244*
X01887Y00249*
X01888Y00255*
X01887Y00262*
X01883Y00267*
X01881Y00268*
Y00274*
X01883Y00275*
X01887Y00281*
X01888Y00287*
X01887Y00293*
X01883Y00298*
X01878Y00302*
X01872Y00303*
G37*
G36*
X02112D02*
X02105Y00302D01*
X021Y00298*
X02097Y00293*
X02097Y00293*
X02091*
X02091Y00293*
X02088Y00298*
X02083Y00302*
X02076Y00303*
X0207Y00302*
X02065Y00298*
X02061Y00293*
X0206Y00287*
X02061Y00281*
X02065Y00275*
X02067Y00274*
Y00268*
X02065Y00267*
X02061Y00262*
X0206Y00255*
X02061Y00249*
X02065Y00244*
X0207Y0024*
X02076Y00239*
X02083Y0024*
X02088Y00244*
X02091Y00249*
X02091Y0025*
X02097*
X02097Y00249*
X021Y00244*
X02105Y0024*
X02112Y00239*
X02118Y0024*
X02123Y00244*
X02127Y00249*
X02128Y00255*
X02127Y00262*
X02123Y00267*
X02121Y00268*
Y00274*
X02123Y00275*
X02127Y00281*
X02128Y00287*
X02127Y00293*
X02123Y00298*
X02118Y00302*
X02112Y00303*
G37*
G36*
X0261Y00295D02*
X02603Y00294D01*
X02598Y00291*
X02597Y00289*
X02591*
X0259Y00291*
X02584Y00294*
X02578Y00295*
X02572Y00294*
X02567Y00291*
X02563Y00285*
X02562Y00279*
X02563Y00273*
X02567Y00267*
X02572Y00264*
X02578Y00263*
X02584Y00264*
X0259Y00267*
X02591Y00269*
X02597*
X02598Y00267*
X02603Y00264*
X0261Y00263*
X02616Y00264*
X02621Y00267*
X02625Y00273*
X02626Y00279*
X02625Y00285*
X02621Y00291*
X02616Y00294*
X0261Y00295*
G37*
G36*
X02444D02*
X02438Y00294D01*
X02433Y00291*
X02432Y00289*
X02426*
X02424Y00291*
X02419Y00294*
X02413Y00295*
X02407Y00294*
X02401Y00291*
X02398Y00285*
X02397Y00279*
X02398Y00273*
X02401Y00267*
X02407Y00264*
X02413Y00263*
X02419Y00264*
X02424Y00267*
X02426Y00269*
X02432*
X02433Y00267*
X02438Y00264*
X02444Y00263*
X02451Y00264*
X02456Y00267*
X02459Y00273*
X02461Y00279*
X02459Y00285*
X02456Y00291*
X02451Y00294*
X02444Y00295*
G37*
G36*
X02937D02*
X0293Y00294D01*
X02925Y00291*
X02924Y00289*
X02918*
X02917Y00291*
X02911Y00294*
X02905Y00295*
X02899Y00294*
X02893Y00291*
X0289Y00285*
X02889Y00279*
X0289Y00273*
X02893Y00267*
X02899Y00264*
X02905Y00263*
X02911Y00264*
X02917Y00267*
X02918Y00269*
X02924*
X02925Y00267*
X0293Y00264*
X02937Y00263*
X02943Y00264*
X02948Y00267*
X02952Y00273*
X02953Y00279*
X02952Y00285*
X02948Y00291*
X02943Y00294*
X02937Y00295*
G37*
G36*
X02748Y00298D02*
X02742Y00297D01*
X02737Y00293*
X02733Y00288*
X02732Y00282*
X02733Y00276*
X02737Y0027*
X02742Y00267*
X02748Y00266*
X02755Y00267*
X0276Y0027*
X02766Y0027*
X02767Y00267*
X02773Y00264*
X02779Y00263*
X02785Y00264*
X02791Y00267*
X02794Y00273*
X02795Y00279*
X02794Y00285*
X02791Y00291*
X02785Y00294*
X02779Y00295*
X02773Y00294*
X02767Y00291*
X02762Y00291*
X0276Y00293*
X02755Y00297*
X02748Y00298*
G37*
G36*
X02151Y00303D02*
X02145Y00302D01*
X0214Y00298*
X02136Y00293*
X02135Y00287*
X02136Y00281*
X0214Y00275*
X02141Y00274*
Y00268*
X0214Y00267*
X02136Y00262*
X02135Y00255*
X02136Y00249*
X0214Y00244*
X02145Y0024*
X02151Y00239*
X02157Y0024*
X02163Y00244*
X02166Y00249*
X02167Y00255*
X02166Y00262*
X02163Y00267*
X02161Y00268*
Y00274*
X02163Y00275*
X02166Y00281*
X02167Y00287*
X02166Y00293*
X02163Y00298*
X02157Y00302*
X02151Y00303*
G37*
G36*
X00285Y00501D02*
X00264Y00499D01*
X00244Y00494*
X00224Y00486*
X00207Y00476*
X00191Y00462*
X00177Y00446*
X00166Y00428*
X00158Y00409*
X00153Y00388*
X00152Y00368*
X00153Y00347*
X00158Y00326*
X00166Y00307*
X00177Y00289*
X00191Y00273*
X00207Y0026*
X00224Y00249*
X00244Y00241*
X00264Y00236*
X00285Y00234*
X00306Y00236*
X00326Y00241*
X00346Y00249*
X00363Y0026*
X00379Y00273*
X00393Y00289*
X00404Y00307*
X00412Y00326*
X00417Y00347*
X00418Y00368*
X00417Y00388*
X00412Y00409*
X00404Y00428*
X00393Y00446*
X00379Y00462*
X00363Y00476*
X00346Y00486*
X00326Y00494*
X00306Y00499*
X00285Y00501*
G37*
%LNtimingcard_pcb-3*%
%LPD*%
G54D142*
X00299Y02581D03*
Y02381D03*
X00099D03*
Y02581D03*
X00299Y02056D03*
Y01856D03*
X00099D03*
Y02056D03*
X00299Y01531D03*
Y01331D03*
X00099D03*
Y01531D03*
X00299Y01006D03*
Y00806D03*
X00099D03*
Y01006D03*
G54D170*
X05127Y02307D03*
G54D172*
X03979Y02489D03*
X05578Y01689D03*
G54D173*
X06569Y03589D03*
X06734D03*
X069D03*
G54D175*
X06119Y04056D03*
G54D176*
X05934Y03937D03*
G54D181*
X02618Y02299D03*
X06978Y0183D03*
X02314Y00933D03*
X02413D03*
X02515D03*
X02905Y00937D03*
X02901Y01106D03*
X0285D03*
X02787D03*
X02728D03*
X02665D03*
X0261D03*
X02511Y01105D03*
X02409Y01106D03*
X02311D03*
X02322Y02429D03*
X02421D03*
X02484D03*
X02783Y02433D03*
X02874Y0229D03*
X02779Y02601D03*
X02688D03*
X0259D03*
X02488Y02574D03*
X02385Y02613D03*
X02279Y02614D03*
X03051Y02732D03*
X03414Y02892D03*
Y02736D03*
X04116Y03597D03*
X03718Y01713D03*
X0359Y01662D03*
X04523Y03736D03*
X0333Y03301D03*
X01721Y01685D03*
X0167D03*
X03877Y03078D03*
X02633Y02921D03*
X02413Y03295D03*
X02258Y03741D03*
X0272Y03494D03*
X06274Y02949D03*
X06362Y02952D03*
X0645Y02462D03*
Y02535D03*
X06452Y02606D03*
X06451Y02673D03*
X0645Y0274D03*
X06587Y01529D03*
X06594Y01673D03*
Y0161D03*
Y01775D03*
Y0172D03*
X03602Y00641D03*
X01674Y01989D03*
X03732Y01418D03*
X03719Y01996D03*
X02685Y02311D03*
X01714Y01595D03*
X02606Y00931D03*
X02881Y02566D03*
X03554Y01941D03*
X0341Y01713D03*
X03414Y01805D03*
X01718Y01792D03*
X03719Y01921D03*
X01675Y01891D03*
X03554Y01991D03*
X03594Y01514D03*
X03406Y01461D03*
X01718Y01497D03*
X01671Y01792D03*
Y01399D03*
X0167Y01595D03*
X01716Y01399D03*
X01671Y01497D03*
X03413Y01573D03*
X01721Y01989D03*
Y0189D03*
X03549Y01413D03*
X03554Y01841D03*
X04039Y03784D03*
X02878Y00249D03*
X02957Y00251D03*
X02447Y00242D03*
X02636Y00247D03*
X02799Y00251D03*
X02546Y00244D03*
X03097Y00251D03*
X02034Y00246D03*
X01916Y00244D03*
X02309Y00246D03*
X03183Y03135D03*
X03277Y02963D03*
X02419Y02788D03*
X02321Y03361D03*
X02473Y0298D03*
X00937Y02317D03*
X01726Y04329D03*
X01788D03*
X04477Y03135D03*
X04064Y02722D03*
X06628Y01372D03*
X03968Y01671D03*
X04131Y01686D03*
X03996Y01711D03*
X0396Y02724D03*
X06647Y03129D03*
X04339Y02725D03*
X0383Y03762D03*
X03395Y04222D03*
X04272Y03135D03*
X04208D03*
X06649Y03003D03*
X04152Y03135D03*
X01248Y02D03*
X04068Y03135D03*
X02674Y03501D03*
X04234Y02725D03*
X06456Y03009D03*
X01691Y04079D03*
X06476Y03231D03*
X04333Y03135D03*
X01261Y02482D03*
X04114Y03135D03*
X06648Y03341D03*
X02888Y04221D03*
X01749Y0411D03*
X0229Y04217D03*
X03744Y03342D03*
X03717Y03072D03*
X05733Y03556D03*
X05676Y03546D03*
X03603Y00682D03*
X06694Y0183D03*
X06699Y01881D03*
X06949Y02095D03*
X06607Y02176D03*
X06395Y02111D03*
X06048Y02171D03*
X06003Y0243D03*
X06274Y02391D03*
X0491Y04203D03*
X04387Y04206D03*
X03777Y04023D03*
X04085Y03892D03*
X04194Y03884D03*
X04431Y03135D03*
X0286Y03787D03*
X02724Y03729D03*
X03531Y0366D03*
X03269Y03788D03*
X01242Y01472D03*
X01256Y00942D03*
X00654Y0079D03*
X00655Y01028D03*
X00654Y01314D03*
X00653Y01551D03*
X00654Y01839D03*
Y02073D03*
Y02365D03*
X00653Y02593D03*
G54D183*
X02531Y03853D03*
Y0283D03*
X00149D03*
Y03853D03*
M02*